FILE_TYPE = MACRO_DRAWING;
SET COLOR_WIRE YELLOW;
SET COLOR_PROP ORANGE;
SET COLOR_DOT WHITE;
SET COLOR_ARC YELLOW;
SET COLOR_BODY GREEN;
SET COLOR_NOTE PURPLE;
SET PROP_DISPLAY VALUE;
SET PAGE_NUMBER P83;
FORCEADD Q_RES..1
(-6025 2975);
FORCEPROP 1 LAST LOCATION R1398
J 0
(-6375 2975);
DISPLAY 0.489362 (-6375 2975);
PAINT SKYBLUE (-6375 2975);
FORCEPROP 0 LAST $SEC 1
J 0
(-6175 3025);
DISPLAY 0.680851 (-6175 3025);
PAINT MONO (-6175 3025);
DISPLAY INVISIBLE (-6175 3025);
FORCEPROP 0 LAST CDS_SEC 1
J 0
(-6175 3025);
DISPLAY 0.680851 (-6175 3025);
DISPLAY INVISIBLE (-6175 3025);
FORCEPROP 1 LASTPIN (-6125 2975) $PN 1
J 0
(-6113 2987);
DISPLAY 0.489362 (-6113 2987);
PAINT MONO (-6113 2987);
FORCEPROP 1 LASTPIN (-5925 2975) $PN 2
J 0
(-5963 2987);
DISPLAY 0.489362 (-5963 2987);
PAINT MONO (-5963 2987);
FORCEPROP 1 LAST VALUE 0
J 2
(-5875 2975);
DISPLAY 0.489362 (-5875 2975);
PAINT SKYBLUE (-5875 2975);
FORCEPROP 1 LAST PACK_TYPE 0402LF
J 0
(-5950 2925);
DISPLAY 0.489362 (-5950 2925);
PAINT SKYBLUE (-5950 2925);
DISPLAY INVISIBLE (-5950 2925);
FORCEPROP 1 LAST PART_NUMBER CS00002JB38
J 0
(-5950 3025);
DISPLAY 0.489362 (-5950 3025);
PAINT SKYBLUE (-5950 3025);
DISPLAY INVISIBLE (-5950 3025);
FORCEPROP 1 LAST TOLERANCE 5%
J 0
(-6025 2925);
DISPLAY 0.489362 (-6025 2925);
PAINT SKYBLUE (-6025 2925);
DISPLAY INVISIBLE (-6025 2925);
FORCEPROP 1 LAST MATERIAL CHIP
J 0
(-5875 2975);
DISPLAY 0.489362 (-5875 2975);
PAINT SKYBLUE (-5875 2975);
DISPLAY INVISIBLE (-5875 2975);
FORCEPROP 1 LAST WATTAGE 1/16W
J 2
(-6050 2875);
DISPLAY 0.489362 (-6050 2875);
PAINT SKYBLUE (-6050 2875);
DISPLAY INVISIBLE (-6050 2875);
FORCEPROP 1 LAST PATH I100
J 0
(-6075 3125);
DISPLAY 0.978723 (-6075 3125);
PAINT WHITE (-6075 3125);
DISPLAY INVISIBLE (-6075 3125);
FORCEPROP 2 LAST CDS_LIB pure_quanta
J 0
(-6025 2975);
DISPLAY INVISIBLE (-6025 2975);
FORCEPROP 2 LAST BOM_COST OCP3.0 
J 0
(-5950 3075);
DISPLAY 0.680851 (-5950 3075);
DISPLAY INVISIBLE (-5950 3075);
FORCEADD OFFPAGE..2
(-4775 1525);
FORCEPROP 2 LAST $XR0 80 
J 0
(-4586 1525);
DISPLAY 0.638298 (-4586 1525);
PAINT MONO (-4586 1525);
FORCEPROP 2 LAST PATH I13
J 0
(-4575 1575);
DISPLAY 0.680851 (-4575 1575);
DISPLAY INVISIBLE (-4575 1575);
FORCEPROP 1 LAST COMMENT_BODY TRUE
J 0
(-4820 1430);
DISPLAY 0.872340 (-4820 1430);
PAINT GREEN (-4820 1430);
DISPLAY INVISIBLE (-4820 1430);
FORCEPROP 1 LAST OFFPAGE TRUE
J 0
(-4450 1400);
DISPLAY 0.872340 (-4450 1400);
PAINT GREEN (-4450 1400);
DISPLAY INVISIBLE (-4450 1400);
FORCEPROP 2 LAST CDS_LIB standard
J 0
(-4775 1525);
DISPLAY INVISIBLE (-4775 1525);
FORCEADD OFFPAGE..2
(-4775 700);
FORCEPROP 2 LAST $XR0 80 
J 0
(-4586 700);
DISPLAY 0.638298 (-4586 700);
PAINT MONO (-4586 700);
FORCEPROP 2 LAST PATH I14
J 0
(-4575 750);
DISPLAY 0.680851 (-4575 750);
DISPLAY INVISIBLE (-4575 750);
FORCEPROP 1 LAST COMMENT_BODY TRUE
J 0
(-4820 605);
DISPLAY 0.872340 (-4820 605);
PAINT GREEN (-4820 605);
DISPLAY INVISIBLE (-4820 605);
FORCEPROP 1 LAST OFFPAGE TRUE
J 0
(-4450 575);
DISPLAY 0.872340 (-4450 575);
PAINT GREEN (-4450 575);
DISPLAY INVISIBLE (-4450 575);
FORCEPROP 2 LAST CDS_LIB standard
J 0
(-4775 700);
DISPLAY INVISIBLE (-4775 700);
FORCEADD UNIVERSAL_POWER..1
(-6450 2050);
FORCEPROP 3 LASTPIN (-6450 2000) SIG_NAME P1V8_STBY\g
J 0
(-6440 2010);
DISPLAY 0.659574 (-6440 2010);
PAINT MONO (-6440 2010);
DISPLAY INVISIBLE (-6440 2010);
FORCEPROP 1 LAST HDL_POWER P1V8_STBY
J 1
(-6450 2100);
DISPLAY 0.489362 (-6450 2100);
PAINT GREEN (-6450 2100);
FORCEPROP 1 LAST PATH I17
J 0
(-6400 2075);
DISPLAY 0.872340 (-6400 2075);
PAINT AQUA (-6400 2075);
DISPLAY INVISIBLE (-6400 2075);
FORCEPROP 2 LAST CDS_LIB pure_quanta_power
J 0
(-6450 2050);
DISPLAY INVISIBLE (-6450 2050);
FORCEPROP 2 LAST BOM_COST OCP3.0 
J 0
(-6450 2150);
DISPLAY 0.680851 (-6450 2150);
DISPLAY INVISIBLE (-6450 2150);
FORCEADD Q_RES..2
(-6450 1775);
FORCEPROP 1 LAST LOCATION R735
J 0
(-6405 1900);
DISPLAY 0.489362 (-6405 1900);
PAINT SKYBLUE (-6405 1900);
FORCEPROP 2 LAST $SEC 1
J 0
(-6400 2000);
DISPLAY 0.680851 (-6400 2000);
PAINT MONO (-6400 2000);
DISPLAY INVISIBLE (-6400 2000);
FORCEPROP 2 LAST CDS_SEC 1
J 0
(-6400 2000);
DISPLAY 0.680851 (-6400 2000);
DISPLAY INVISIBLE (-6400 2000);
FORCEPROP 1 LASTPIN (-6450 1875) $PN 1
J 0
(-6445 1837);
DISPLAY 0.489362 (-6445 1837);
PAINT MONO (-6445 1837);
FORCEPROP 1 LASTPIN (-6450 1675) $PN 2
J 0
(-6445 1685);
DISPLAY 0.489362 (-6445 1685);
PAINT MONO (-6445 1685);
FORCEPROP 1 LAST PACK_TYPE 0402LF
J 0
(-6410 1600);
DISPLAY 0.489362 (-6410 1600);
PAINT SKYBLUE (-6410 1600);
FORCEPROP 1 LAST PART_NUMBER TMP_QCS24702JB38
J 0
(-6410 1650);
DISPLAY 0.489362 (-6410 1650);
PAINT SKYBLUE (-6410 1650);
FORCEPROP 1 LAST VALUE 4.7K
J 0
(-6405 1850);
DISPLAY 0.489362 (-6405 1850);
PAINT SKYBLUE (-6405 1850);
FORCEPROP 1 LAST TOLERANCE 5%
J 0
(-6405 1800);
DISPLAY 0.489362 (-6405 1800);
PAINT SKYBLUE (-6405 1800);
FORCEPROP 1 LAST MATERIAL CHIP
J 0
(-6410 1700);
DISPLAY 0.489362 (-6410 1700);
PAINT SKYBLUE (-6410 1700);
FORCEPROP 1 LAST WATTAGE 1/16W
J 0
(-6410 1750);
DISPLAY 0.489362 (-6410 1750);
PAINT SKYBLUE (-6410 1750);
FORCEPROP 1 LAST PATH I18
J 0
(-6400 1950);
DISPLAY 0.978723 (-6400 1950);
PAINT WHITE (-6400 1950);
DISPLAY INVISIBLE (-6400 1950);
FORCEPROP 2 LAST BOM_COST OCP3.0 
J 0
(-6400 1950);
DISPLAY 0.680851 (-6400 1950);
DISPLAY INVISIBLE (-6400 1950);
FORCEPROP 2 LAST CDS_LIB pure_quanta
J 0
(-6450 1775);
DISPLAY INVISIBLE (-6450 1775);
FORCEADD Q_RES..2
(-8275 1750);
FORCEPROP 1 LAST LOCATION R1445
J 0
(-8250 1825);
DISPLAY 0.489362 (-8250 1825);
PAINT SKYBLUE (-8250 1825);
FORCEPROP 0 LAST $SEC 1
J 0
(-8250 1850);
DISPLAY 0.680851 (-8250 1850);
PAINT MONO (-8250 1850);
DISPLAY INVISIBLE (-8250 1850);
FORCEPROP 0 LAST CDS_SEC 1
J 0
(-8250 1850);
DISPLAY 0.680851 (-8250 1850);
DISPLAY INVISIBLE (-8250 1850);
FORCEPROP 1 LASTPIN (-8275 1850) $PN 1
J 0
(-8270 1812);
DISPLAY 0.489362 (-8270 1812);
PAINT MONO (-8270 1812);
FORCEPROP 1 LASTPIN (-8275 1650) $PN 2
J 0
(-8270 1660);
DISPLAY 0.489362 (-8270 1660);
PAINT MONO (-8270 1660);
FORCEPROP 1 LAST VALUE 4.7K
J 0
(-8250 1775);
DISPLAY 0.489362 (-8250 1775);
PAINT SKYBLUE (-8250 1775);
FORCEPROP 1 LAST PACK_TYPE 0402LF
J 0
(-8235 1575);
DISPLAY 0.489362 (-8235 1575);
PAINT SKYBLUE (-8235 1575);
DISPLAY INVISIBLE (-8235 1575);
FORCEPROP 1 LAST PART_NUMBER TMP_QCS24702JB38
J 0
(-8235 1625);
DISPLAY 0.489362 (-8235 1625);
PAINT SKYBLUE (-8235 1625);
DISPLAY INVISIBLE (-8235 1625);
FORCEPROP 1 LAST TOLERANCE 5%
J 0
(-8230 1775);
DISPLAY 0.489362 (-8230 1775);
PAINT SKYBLUE (-8230 1775);
DISPLAY INVISIBLE (-8230 1775);
FORCEPROP 1 LAST MATERIAL CHIP
J 0
(-8235 1675);
DISPLAY 0.489362 (-8235 1675);
PAINT SKYBLUE (-8235 1675);
DISPLAY INVISIBLE (-8235 1675);
FORCEPROP 1 LAST WATTAGE 1/16W
J 0
(-8235 1725);
DISPLAY 0.489362 (-8235 1725);
PAINT SKYBLUE (-8235 1725);
DISPLAY INVISIBLE (-8235 1725);
FORCEPROP 1 LAST PATH I181
J 0
(-8225 1925);
DISPLAY 0.978723 (-8225 1925);
PAINT WHITE (-8225 1925);
DISPLAY INVISIBLE (-8225 1925);
FORCEPROP 2 LAST BOM_COST OCP3.0 
J 0
(-8225 1925);
DISPLAY 0.680851 (-8225 1925);
DISPLAY INVISIBLE (-8225 1925);
FORCEPROP 2 LAST CDS_LIB pure_quanta
J 0
(-8275 1750);
DISPLAY INVISIBLE (-8275 1750);
FORCEADD UNIVERSAL_POWER..1
(-8275 1950);
FORCEPROP 3 LASTPIN (-8275 1900) SIG_NAME P3V3_STBY\g
J 0
(-8265 1910);
DISPLAY 0.659574 (-8265 1910);
PAINT MONO (-8265 1910);
DISPLAY INVISIBLE (-8265 1910);
FORCEPROP 1 LAST HDL_POWER P3V3_STBY
J 1
(-8275 2000);
DISPLAY 0.489362 (-8275 2000);
PAINT GREEN (-8275 2000);
FORCEPROP 1 LAST PATH I182
J 0
(-8225 1975);
DISPLAY 0.872340 (-8225 1975);
PAINT AQUA (-8225 1975);
DISPLAY INVISIBLE (-8225 1975);
FORCEPROP 2 LAST CDS_LIB pure_quanta_power
J 0
(-8275 1950);
DISPLAY INVISIBLE (-8275 1950);
FORCEPROP 2 LAST BOM_COST OCP3.0 
J 0
(-8275 2050);
DISPLAY 0.680851 (-8275 2050);
DISPLAY INVISIBLE (-8275 2050);
FORCEADD UNIVERSAL_POWER..1
(-8250 1125);
FORCEPROP 3 LASTPIN (-8250 1075) SIG_NAME P3V3_STBY\g
J 0
(-8240 1085);
DISPLAY 0.659574 (-8240 1085);
PAINT MONO (-8240 1085);
DISPLAY INVISIBLE (-8240 1085);
FORCEPROP 1 LAST HDL_POWER P3V3_STBY
J 1
(-8250 1175);
DISPLAY 0.489362 (-8250 1175);
PAINT GREEN (-8250 1175);
FORCEPROP 1 LAST PATH I183
J 0
(-8200 1150);
DISPLAY 0.872340 (-8200 1150);
PAINT AQUA (-8200 1150);
DISPLAY INVISIBLE (-8200 1150);
FORCEPROP 2 LAST BOM_COST OCP3.0 
J 0
(-8250 1225);
DISPLAY 0.680851 (-8250 1225);
DISPLAY INVISIBLE (-8250 1225);
FORCEPROP 2 LAST CDS_LIB pure_quanta_power
J 0
(-8250 1125);
DISPLAY INVISIBLE (-8250 1125);
FORCEADD Q_RES..2
(-8250 925);
FORCEPROP 1 LAST LOCATION R1446
J 0
(-8205 1050);
DISPLAY 0.489362 (-8205 1050);
PAINT SKYBLUE (-8205 1050);
FORCEPROP 0 LAST $SEC 1
J 0
(-8200 1100);
DISPLAY 0.680851 (-8200 1100);
PAINT MONO (-8200 1100);
DISPLAY INVISIBLE (-8200 1100);
FORCEPROP 0 LAST CDS_SEC 1
J 0
(-8200 1100);
DISPLAY 0.680851 (-8200 1100);
DISPLAY INVISIBLE (-8200 1100);
FORCEPROP 1 LASTPIN (-8250 1025) $PN 1
J 0
(-8245 987);
DISPLAY 0.489362 (-8245 987);
PAINT MONO (-8245 987);
FORCEPROP 1 LASTPIN (-8250 825) $PN 2
J 0
(-8245 835);
DISPLAY 0.489362 (-8245 835);
PAINT MONO (-8245 835);
FORCEPROP 1 LAST VALUE 4.7K
J 0
(-8225 950);
DISPLAY 0.489362 (-8225 950);
PAINT SKYBLUE (-8225 950);
FORCEPROP 1 LAST PACK_TYPE 0402LF
J 0
(-8210 750);
DISPLAY 0.489362 (-8210 750);
PAINT SKYBLUE (-8210 750);
DISPLAY INVISIBLE (-8210 750);
FORCEPROP 1 LAST PART_NUMBER TMP_QCS24702JB38
J 0
(-8210 800);
DISPLAY 0.489362 (-8210 800);
PAINT SKYBLUE (-8210 800);
DISPLAY INVISIBLE (-8210 800);
FORCEPROP 1 LAST TOLERANCE 5%
J 0
(-8205 950);
DISPLAY 0.489362 (-8205 950);
PAINT SKYBLUE (-8205 950);
DISPLAY INVISIBLE (-8205 950);
FORCEPROP 1 LAST MATERIAL CHIP
J 0
(-8210 850);
DISPLAY 0.489362 (-8210 850);
PAINT SKYBLUE (-8210 850);
DISPLAY INVISIBLE (-8210 850);
FORCEPROP 1 LAST WATTAGE 1/16W
J 0
(-8210 900);
DISPLAY 0.489362 (-8210 900);
PAINT SKYBLUE (-8210 900);
DISPLAY INVISIBLE (-8210 900);
FORCEPROP 1 LAST PATH I184
J 0
(-8200 1100);
DISPLAY 0.978723 (-8200 1100);
PAINT WHITE (-8200 1100);
DISPLAY INVISIBLE (-8200 1100);
FORCEPROP 2 LAST CDS_LIB pure_quanta
J 0
(-8250 925);
DISPLAY INVISIBLE (-8250 925);
FORCEPROP 2 LAST BOM_COST OCP3.0 
J 0
(-8200 1100);
DISPLAY 0.680851 (-8200 1100);
DISPLAY INVISIBLE (-8200 1100);
FORCEADD UNIVERSAL_POWER..1
(-2950 1800);
FORCEPROP 3 LASTPIN (-2950 1750) SIG_NAME P3V3_STBY\g
J 0
(-2940 1760);
DISPLAY 0.659574 (-2940 1760);
PAINT MONO (-2940 1760);
DISPLAY INVISIBLE (-2940 1760);
FORCEPROP 1 LAST HDL_POWER P3V3_STBY
J 1
(-2950 1850);
DISPLAY 0.489362 (-2950 1850);
PAINT GREEN (-2950 1850);
FORCEPROP 1 LAST PATH I185
J 0
(-2900 1825);
DISPLAY 0.872340 (-2900 1825);
PAINT AQUA (-2900 1825);
DISPLAY INVISIBLE (-2900 1825);
FORCEPROP 2 LAST CDS_LIB pure_quanta_power
J 0
(-2950 1800);
DISPLAY INVISIBLE (-2950 1800);
FORCEADD UNIVERSAL_POWER..1
(-5850 4825);
FORCEPROP 3 LASTPIN (-5850 4775) SIG_NAME P3V3_STBY\g
J 0
(-5840 4785);
DISPLAY 0.659574 (-5840 4785);
PAINT MONO (-5840 4785);
DISPLAY INVISIBLE (-5840 4785);
FORCEPROP 1 LAST HDL_POWER P3V3_STBY
J 1
(-5850 4875);
DISPLAY 0.489362 (-5850 4875);
PAINT GREEN (-5850 4875);
FORCEPROP 1 LAST PATH I186
J 0
(-5800 4850);
DISPLAY 0.872340 (-5800 4850);
PAINT AQUA (-5800 4850);
DISPLAY INVISIBLE (-5800 4850);
FORCEPROP 2 LAST BOM_COST OCP3.0 
J 0
(-5850 4925);
DISPLAY 0.680851 (-5850 4925);
DISPLAY INVISIBLE (-5850 4925);
FORCEPROP 2 LAST CDS_LIB pure_quanta_power
J 0
(-5850 4825);
DISPLAY INVISIBLE (-5850 4825);
FORCEADD OFFPAGE..2
(-5700 4300);
FORCEPROP 2 LAST $XR0 117 
J 0
(-5511 4300);
DISPLAY 0.638298 (-5511 4300);
PAINT MONO (-5511 4300);
FORCEPROP 2 LAST PATH I187
J 0
(-5400 4350);
DISPLAY 0.680851 (-5400 4350);
DISPLAY INVISIBLE (-5400 4350);
FORCEPROP 1 LAST COMMENT_BODY TRUE
J 0
(-5745 4205);
DISPLAY 0.872340 (-5745 4205);
PAINT GREEN (-5745 4205);
DISPLAY INVISIBLE (-5745 4205);
FORCEPROP 1 LAST OFFPAGE TRUE
J 0
(-5375 4175);
DISPLAY 0.872340 (-5375 4175);
PAINT GREEN (-5375 4175);
DISPLAY INVISIBLE (-5375 4175);
FORCEPROP 2 LAST CDS_LIB standard
J 0
(-5700 4300);
DISPLAY INVISIBLE (-5700 4300);
FORCEADD Q_RES..2
(-5850 4550);
FORCEPROP 1 LAST LOCATION R1338
J 0
(-5805 4675);
DISPLAY 0.489362 (-5805 4675);
PAINT SKYBLUE (-5805 4675);
FORCEPROP 0 LAST $SEC 1
J 0
(-5800 4725);
DISPLAY 0.680851 (-5800 4725);
PAINT MONO (-5800 4725);
DISPLAY INVISIBLE (-5800 4725);
FORCEPROP 0 LAST CDS_SEC 1
J 0
(-5800 4725);
DISPLAY 0.680851 (-5800 4725);
DISPLAY INVISIBLE (-5800 4725);
FORCEPROP 1 LASTPIN (-5850 4650) $PN 1
J 0
(-5845 4612);
DISPLAY 0.489362 (-5845 4612);
PAINT MONO (-5845 4612);
FORCEPROP 1 LASTPIN (-5850 4450) $PN 2
J 0
(-5845 4460);
DISPLAY 0.489362 (-5845 4460);
PAINT MONO (-5845 4460);
FORCEPROP 1 LAST PACK_TYPE 0402LF
J 0
(-5810 4375);
DISPLAY 0.489362 (-5810 4375);
PAINT SKYBLUE (-5810 4375);
FORCEPROP 1 LAST PART_NUMBER TMP_QCS24702JB38
J 0
(-5810 4425);
DISPLAY 0.489362 (-5810 4425);
PAINT SKYBLUE (-5810 4425);
FORCEPROP 1 LAST VALUE 4.7K
J 0
(-5805 4625);
DISPLAY 0.489362 (-5805 4625);
PAINT SKYBLUE (-5805 4625);
FORCEPROP 1 LAST TOLERANCE 5%
J 0
(-5805 4575);
DISPLAY 0.489362 (-5805 4575);
PAINT SKYBLUE (-5805 4575);
FORCEPROP 1 LAST MATERIAL CHIP
J 0
(-5810 4475);
DISPLAY 0.489362 (-5810 4475);
PAINT SKYBLUE (-5810 4475);
FORCEPROP 1 LAST WATTAGE 1/16W
J 0
(-5810 4525);
DISPLAY 0.489362 (-5810 4525);
PAINT SKYBLUE (-5810 4525);
FORCEPROP 1 LAST PATH I188
J 0
(-5800 4725);
DISPLAY 0.978723 (-5800 4725);
PAINT WHITE (-5800 4725);
DISPLAY INVISIBLE (-5800 4725);
FORCEPROP 2 LAST BOM_COST OCP3.0 
J 0
(-5800 4725);
DISPLAY 0.680851 (-5800 4725);
DISPLAY INVISIBLE (-5800 4725);
FORCEPROP 2 LAST CDS_LIB pure_quanta
J 0
(-5850 4550);
DISPLAY INVISIBLE (-5850 4550);
FORCEADD Q_RES..1
(-6425 4300);
FORCEPROP 1 LAST LOCATION R71
J 0
(-6300 4300);
DISPLAY 0.489362 (-6300 4300);
PAINT SKYBLUE (-6300 4300);
FORCEPROP 0 LAST $SEC 1
J 0
(-6300 4325);
DISPLAY 0.680851 (-6300 4325);
PAINT MONO (-6300 4325);
DISPLAY INVISIBLE (-6300 4325);
FORCEPROP 0 LAST CDS_SEC 1
J 0
(-6300 4325);
DISPLAY 0.680851 (-6300 4325);
DISPLAY INVISIBLE (-6300 4325);
FORCEPROP 1 LASTPIN (-6525 4300) $PN 1
J 0
(-6513 4312);
DISPLAY 0.489362 (-6513 4312);
PAINT MONO (-6513 4312);
FORCEPROP 1 LASTPIN (-6325 4300) $PN 2
J 0
(-6363 4312);
DISPLAY 0.489362 (-6363 4312);
PAINT MONO (-6363 4312);
FORCEPROP 1 LAST VALUE 33
J 2
(-6550 4300);
DISPLAY 0.489362 (-6550 4300);
PAINT SKYBLUE (-6550 4300);
FORCEPROP 2 LAST ROOM RST_CPU0_PLD_TO_DIMM
J 2
(-6400 4400);
DISPLAY 0.744681 (-6400 4400);
PAINT RED (-6400 4400);
DISPLAY INVISIBLE (-6400 4400);
FORCEPROP 1 LAST PACK_TYPE 0402LF
J 2
(-6250 4225);
DISPLAY 0.489362 (-6250 4225);
PAINT SKYBLUE (-6250 4225);
DISPLAY INVISIBLE (-6250 4225);
FORCEPROP 1 LAST PART_NUMBER CS03302JB29
J 2
(-6325 4350);
DISPLAY 0.489362 (-6325 4350);
PAINT SKYBLUE (-6325 4350);
DISPLAY INVISIBLE (-6325 4350);
FORCEPROP 1 LAST TOLERANCE 5%
J 0
(-6550 4275);
DISPLAY 0.489362 (-6550 4275);
PAINT SKYBLUE (-6550 4275);
DISPLAY INVISIBLE (-6550 4275);
FORCEPROP 1 LAST MATERIAL CHIP
J 2
(-6250 4275);
DISPLAY 0.489362 (-6250 4275);
PAINT SKYBLUE (-6250 4275);
DISPLAY INVISIBLE (-6250 4275);
FORCEPROP 1 LAST WATTAGE 1/16W
J 2
(-6500 4225);
DISPLAY 0.489362 (-6500 4225);
PAINT SKYBLUE (-6500 4225);
DISPLAY INVISIBLE (-6500 4225);
FORCEPROP 1 LAST PATH I189
J 0
(-6475 4450);
DISPLAY 0.978723 (-6475 4450);
PAINT WHITE (-6475 4450);
DISPLAY INVISIBLE (-6475 4450);
FORCEPROP 2 LAST BOM_COST MEM
J 2
(-6400 4450);
DISPLAY 0.744681 (-6400 4450);
PAINT WHITE (-6400 4450);
DISPLAY INVISIBLE (-6400 4450);
FORCEPROP 2 LAST CDS_LIB pure_quanta
J 0
(-6425 4300);
DISPLAY INVISIBLE (-6425 4300);
FORCEADD Q_RES..1
(-5950 1525);
FORCEPROP 1 LAST LOCATION R1355
J 0
(-6275 1525);
DISPLAY 0.489362 (-6275 1525);
PAINT SKYBLUE (-6275 1525);
FORCEPROP 2 LAST $SEC 1
J 0
(-6000 1725);
DISPLAY 0.680851 (-6000 1725);
PAINT MONO (-6000 1725);
DISPLAY INVISIBLE (-6000 1725);
FORCEPROP 2 LAST CDS_SEC 1
J 0
(-6000 1725);
DISPLAY 0.680851 (-6000 1725);
DISPLAY INVISIBLE (-6000 1725);
FORCEPROP 1 LASTPIN (-6050 1525) $PN 1
J 0
(-6038 1537);
DISPLAY 0.489362 (-6038 1537);
PAINT MONO (-6038 1537);
FORCEPROP 1 LASTPIN (-5850 1525) $PN 2
J 0
(-5888 1537);
DISPLAY 0.489362 (-5888 1537);
PAINT MONO (-5888 1537);
FORCEPROP 1 LAST VALUE 33
J 2
(-5750 1525);
DISPLAY 0.489362 (-5750 1525);
PAINT SKYBLUE (-5750 1525);
FORCEPROP 1 LAST MATERIAL CHIP
J 0
(-5700 1525);
DISPLAY 0.489362 (-5700 1525);
PAINT SKYBLUE (-5700 1525);
FORCEPROP 1 LAST PACK_TYPE 0402LF
J 0
(-5875 1475);
DISPLAY 0.489362 (-5875 1475);
PAINT SKYBLUE (-5875 1475);
DISPLAY INVISIBLE (-5875 1475);
FORCEPROP 1 LAST PART_NUMBER CS03302JB29
J 0
(-5875 1575);
DISPLAY 0.489362 (-5875 1575);
PAINT SKYBLUE (-5875 1575);
DISPLAY INVISIBLE (-5875 1575);
FORCEPROP 1 LAST TOLERANCE 5%
J 0
(-5950 1475);
DISPLAY 0.489362 (-5950 1475);
PAINT SKYBLUE (-5950 1475);
DISPLAY INVISIBLE (-5950 1475);
FORCEPROP 1 LAST WATTAGE 1/16W
J 2
(-5975 1425);
DISPLAY 0.489362 (-5975 1425);
PAINT SKYBLUE (-5975 1425);
DISPLAY INVISIBLE (-5975 1425);
FORCEPROP 1 LAST PATH I19
J 0
(-6000 1675);
DISPLAY 0.978723 (-6000 1675);
PAINT WHITE (-6000 1675);
DISPLAY INVISIBLE (-6000 1675);
FORCEPROP 2 LAST BOM_COST OCP3.0 
J 0
(-5875 1625);
DISPLAY 0.680851 (-5875 1625);
DISPLAY INVISIBLE (-5875 1625);
FORCEPROP 2 LAST CDS_LIB pure_quanta
J 0
(-5950 1525);
DISPLAY INVISIBLE (-5950 1525);
FORCEADD Q_RES..1
(-2000 1350);
FORCEPROP 1 LAST LOCATION R1391
J 0
(-2225 1350);
DISPLAY 0.489362 (-2225 1350);
PAINT SKYBLUE (-2225 1350);
FORCEPROP 2 LAST $SEC 1
J 0
(-2050 1550);
DISPLAY 0.680851 (-2050 1550);
PAINT MONO (-2050 1550);
DISPLAY INVISIBLE (-2050 1550);
FORCEPROP 2 LAST CDS_SEC 1
J 0
(-2050 1550);
DISPLAY 0.680851 (-2050 1550);
DISPLAY INVISIBLE (-2050 1550);
FORCEPROP 1 LASTPIN (-2100 1350) $PN 1
J 0
(-2088 1362);
DISPLAY 0.489362 (-2088 1362);
PAINT MONO (-2088 1362);
FORCEPROP 1 LASTPIN (-1900 1350) $PN 2
J 0
(-1938 1362);
DISPLAY 0.489362 (-1938 1362);
PAINT MONO (-1938 1362);
FORCEPROP 1 LAST VALUE 33
J 2
(-1850 1350);
DISPLAY 0.489362 (-1850 1350);
PAINT SKYBLUE (-1850 1350);
FORCEPROP 1 LAST PACK_TYPE 0402LF
J 0
(-1950 1275);
DISPLAY 0.489362 (-1950 1275);
PAINT SKYBLUE (-1950 1275);
DISPLAY INVISIBLE (-1950 1275);
FORCEPROP 1 LAST PART_NUMBER CS03302JB29
J 0
(-1975 1400);
DISPLAY 0.489362 (-1975 1400);
PAINT SKYBLUE (-1975 1400);
DISPLAY INVISIBLE (-1975 1400);
FORCEPROP 1 LAST TOLERANCE 5%
J 0
(-2025 1275);
DISPLAY 0.489362 (-2025 1275);
PAINT SKYBLUE (-2025 1275);
DISPLAY INVISIBLE (-2025 1275);
FORCEPROP 1 LAST MATERIAL CHIP
J 0
(-1575 1275);
DISPLAY 0.489362 (-1575 1275);
PAINT SKYBLUE (-1575 1275);
DISPLAY INVISIBLE (-1575 1275);
FORCEPROP 1 LAST WATTAGE 1/16W
J 2
(-1600 1275);
DISPLAY 0.489362 (-1600 1275);
PAINT SKYBLUE (-1600 1275);
DISPLAY INVISIBLE (-1600 1275);
FORCEPROP 1 LAST PATH I190
J 0
(-2050 1500);
DISPLAY 0.978723 (-2050 1500);
PAINT WHITE (-2050 1500);
DISPLAY INVISIBLE (-2050 1500);
FORCEPROP 2 LAST CDS_LIB pure_quanta
J 0
(-2000 1350);
DISPLAY INVISIBLE (-2000 1350);
FORCEADD Q_RES..1
(-1975 2750);
FORCEPROP 1 LAST LOCATION R1387
J 0
(-2175 2750);
DISPLAY 0.489362 (-2175 2750);
PAINT SKYBLUE (-2175 2750);
FORCEPROP 2 LAST $SEC 1
J 0
(-2025 2950);
DISPLAY 0.680851 (-2025 2950);
PAINT MONO (-2025 2950);
DISPLAY INVISIBLE (-2025 2950);
FORCEPROP 2 LAST CDS_SEC 1
J 0
(-2025 2950);
DISPLAY 0.680851 (-2025 2950);
DISPLAY INVISIBLE (-2025 2950);
FORCEPROP 1 LASTPIN (-2075 2750) $PN 1
J 0
(-2063 2762);
DISPLAY 0.489362 (-2063 2762);
PAINT MONO (-2063 2762);
FORCEPROP 1 LASTPIN (-1875 2750) $PN 2
J 0
(-1913 2762);
DISPLAY 0.489362 (-1913 2762);
PAINT MONO (-1913 2762);
FORCEPROP 1 LAST VALUE 33
J 2
(-1825 2750);
DISPLAY 0.489362 (-1825 2750);
PAINT SKYBLUE (-1825 2750);
FORCEPROP 1 LAST PACK_TYPE 0402LF
J 0
(-1925 2675);
DISPLAY 0.489362 (-1925 2675);
PAINT SKYBLUE (-1925 2675);
DISPLAY INVISIBLE (-1925 2675);
FORCEPROP 1 LAST PART_NUMBER CS03302JB29
J 0
(-1950 2800);
DISPLAY 0.489362 (-1950 2800);
PAINT SKYBLUE (-1950 2800);
DISPLAY INVISIBLE (-1950 2800);
FORCEPROP 1 LAST TOLERANCE 5%
J 0
(-2000 2675);
DISPLAY 0.489362 (-2000 2675);
PAINT SKYBLUE (-2000 2675);
DISPLAY INVISIBLE (-2000 2675);
FORCEPROP 1 LAST MATERIAL CHIP
J 0
(-1550 2675);
DISPLAY 0.489362 (-1550 2675);
PAINT SKYBLUE (-1550 2675);
DISPLAY INVISIBLE (-1550 2675);
FORCEPROP 1 LAST WATTAGE 1/16W
J 2
(-1575 2675);
DISPLAY 0.489362 (-1575 2675);
PAINT SKYBLUE (-1575 2675);
DISPLAY INVISIBLE (-1575 2675);
FORCEPROP 1 LAST PATH I191
J 0
(-2025 2900);
DISPLAY 0.978723 (-2025 2900);
PAINT WHITE (-2025 2900);
DISPLAY INVISIBLE (-2025 2900);
FORCEPROP 2 LAST CDS_LIB pure_quanta
J 0
(-1975 2750);
DISPLAY INVISIBLE (-1975 2750);
FORCEADD OFFPAGE..2
(-975 1350);
FORCEPROP 2 LAST $XR0 152 
J 0
(-786 1350);
DISPLAY 0.638298 (-786 1350);
PAINT MONO (-786 1350);
FORCEPROP 2 LAST PATH I192
J 0
(-775 1400);
DISPLAY 0.680851 (-775 1400);
DISPLAY INVISIBLE (-775 1400);
FORCEPROP 1 LAST COMMENT_BODY TRUE
J 0
(-1020 1255);
DISPLAY 0.872340 (-1020 1255);
PAINT GREEN (-1020 1255);
DISPLAY INVISIBLE (-1020 1255);
FORCEPROP 1 LAST OFFPAGE TRUE
J 0
(-650 1225);
DISPLAY 0.872340 (-650 1225);
PAINT GREEN (-650 1225);
DISPLAY INVISIBLE (-650 1225);
FORCEPROP 2 LAST CDS_LIB standard
J 0
(-975 1350);
DISPLAY INVISIBLE (-975 1350);
FORCEADD OFFPAGE..2
(-950 2750);
FORCEPROP 2 LAST $XR0 152 
J 0
(-761 2750);
DISPLAY 0.638298 (-761 2750);
PAINT MONO (-761 2750);
FORCEPROP 2 LAST PATH I193
J 0
(-750 2800);
DISPLAY 0.680851 (-750 2800);
DISPLAY INVISIBLE (-750 2800);
FORCEPROP 1 LAST COMMENT_BODY TRUE
J 0
(-995 2655);
DISPLAY 0.872340 (-995 2655);
PAINT GREEN (-995 2655);
DISPLAY INVISIBLE (-995 2655);
FORCEPROP 1 LAST OFFPAGE TRUE
J 0
(-625 2625);
DISPLAY 0.872340 (-625 2625);
PAINT GREEN (-625 2625);
DISPLAY INVISIBLE (-625 2625);
FORCEPROP 2 LAST CDS_LIB standard
J 0
(-950 2750);
DISPLAY INVISIBLE (-950 2750);
FORCEADD OFFPAGE..2
(-1475 4300);
FORCEPROP 2 LAST $XR0 210 
J 0
(-1286 4300);
DISPLAY 0.638298 (-1286 4300);
PAINT MONO (-1286 4300);
FORCEPROP 2 LAST PATH I194
J 0
(-1275 4350);
DISPLAY 0.680851 (-1275 4350);
DISPLAY INVISIBLE (-1275 4350);
FORCEPROP 1 LAST COMMENT_BODY TRUE
J 0
(-1520 4205);
DISPLAY 0.872340 (-1520 4205);
PAINT GREEN (-1520 4205);
DISPLAY INVISIBLE (-1520 4205);
FORCEPROP 1 LAST OFFPAGE TRUE
J 0
(-1150 4175);
DISPLAY 0.872340 (-1150 4175);
PAINT GREEN (-1150 4175);
DISPLAY INVISIBLE (-1150 4175);
FORCEPROP 2 LAST CDS_LIB standard
J 0
(-1475 4300);
DISPLAY INVISIBLE (-1475 4300);
FORCEADD Q_RES..1
(-2100 4300);
FORCEPROP 1 LAST LOCATION R1426
J 0
(-2350 4300);
DISPLAY 0.489362 (-2350 4300);
PAINT SKYBLUE (-2350 4300);
FORCEPROP 0 LAST $SEC 1
J 0
(-1925 4325);
DISPLAY 0.680851 (-1925 4325);
PAINT MONO (-1925 4325);
DISPLAY INVISIBLE (-1925 4325);
FORCEPROP 0 LAST CDS_SEC 1
J 0
(-1925 4325);
DISPLAY 0.680851 (-1925 4325);
DISPLAY INVISIBLE (-1925 4325);
FORCEPROP 1 LASTPIN (-2200 4300) $PN 1
J 0
(-2188 4312);
DISPLAY 0.489362 (-2188 4312);
PAINT MONO (-2188 4312);
FORCEPROP 1 LASTPIN (-2000 4300) $PN 2
J 0
(-2038 4312);
DISPLAY 0.489362 (-2038 4312);
PAINT MONO (-2038 4312);
FORCEPROP 1 LAST VALUE 33
J 2
(-1925 4300);
DISPLAY 0.489362 (-1925 4300);
PAINT SKYBLUE (-1925 4300);
FORCEPROP 1 LAST PACK_TYPE 0402LF
J 0
(-2025 4250);
DISPLAY 0.489362 (-2025 4250);
PAINT SKYBLUE (-2025 4250);
DISPLAY INVISIBLE (-2025 4250);
FORCEPROP 1 LAST PART_NUMBER CS03302JB29
J 0
(-2150 4400);
DISPLAY 0.978723 (-2150 4400);
PAINT SKYBLUE (-2150 4400);
DISPLAY INVISIBLE (-2150 4400);
FORCEPROP 1 LAST TOLERANCE 5%
J 0
(-2100 4200);
DISPLAY 0.978723 (-2100 4200);
PAINT SKYBLUE (-2100 4200);
DISPLAY INVISIBLE (-2100 4200);
FORCEPROP 1 LAST MATERIAL CHIP
J 0
(-2150 4250);
DISPLAY 0.489362 (-2150 4250);
PAINT SKYBLUE (-2150 4250);
DISPLAY INVISIBLE (-2150 4250);
FORCEPROP 1 LAST WATTAGE 1/16W
J 2
(-2125 4150);
DISPLAY 0.978723 (-2125 4150);
PAINT SKYBLUE (-2125 4150);
DISPLAY INVISIBLE (-2125 4150);
FORCEPROP 1 LAST PATH I195
J 0
(-2150 4450);
DISPLAY 0.978723 (-2150 4450);
PAINT WHITE (-2150 4450);
DISPLAY INVISIBLE (-2150 4450);
FORCEPROP 2 LAST CDS_LIB pure_quanta
J 0
(-2100 4300);
DISPLAY INVISIBLE (-2100 4300);
FORCEADD UNIVERSAL_POWER..1
(-2975 4800);
FORCEPROP 3 LASTPIN (-2975 4750) SIG_NAME P12V_STBY\g
J 0
(-2965 4760);
DISPLAY 0.659574 (-2965 4760);
PAINT MONO (-2965 4760);
DISPLAY INVISIBLE (-2965 4760);
FORCEPROP 1 LAST HDL_POWER P12V_STBY
J 1
(-2975 4850);
DISPLAY 0.489362 (-2975 4850);
PAINT GREEN (-2975 4850);
FORCEPROP 1 LAST PATH I196
J 0
(-2925 4825);
DISPLAY 0.872340 (-2925 4825);
PAINT AQUA (-2925 4825);
DISPLAY INVISIBLE (-2925 4825);
FORCEPROP 2 LAST BOM_COST OCP3.0 
J 0
(-2975 4900);
DISPLAY 0.680851 (-2975 4900);
DISPLAY INVISIBLE (-2975 4900);
FORCEPROP 2 LAST CDS_LIB pure_quanta_power
J 0
(-2975 4800);
DISPLAY INVISIBLE (-2975 4800);
FORCEADD Q_RES..2
(-2975 4600);
FORCEPROP 1 LAST LOCATION R887
J 0
(-2930 4725);
DISPLAY 0.489362 (-2930 4725);
PAINT SKYBLUE (-2930 4725);
FORCEPROP 0 LAST $SEC 1
J 0
(-2925 4775);
DISPLAY 0.680851 (-2925 4775);
PAINT MONO (-2925 4775);
DISPLAY INVISIBLE (-2925 4775);
FORCEPROP 0 LAST CDS_SEC 1
J 0
(-2925 4775);
DISPLAY 1.021277 (-2925 4775);
DISPLAY INVISIBLE (-2925 4775);
FORCEPROP 1 LASTPIN (-2975 4700) $PN 1
J 0
(-2970 4662);
DISPLAY 0.489362 (-2970 4662);
PAINT MONO (-2970 4662);
FORCEPROP 1 LASTPIN (-2975 4500) $PN 2
J 0
(-2970 4510);
DISPLAY 0.489362 (-2970 4510);
PAINT MONO (-2970 4510);
FORCEPROP 1 LAST VALUE 10K
J 0
(-2930 4675);
DISPLAY 0.489362 (-2930 4675);
PAINT SKYBLUE (-2930 4675);
FORCEPROP 1 LAST TOLERANCE 5%
J 0
(-2930 4625);
DISPLAY 0.489362 (-2930 4625);
PAINT SKYBLUE (-2930 4625);
FORCEPROP 1 LAST WATTAGE 1/16W
J 0
(-2935 4575);
DISPLAY 0.489362 (-2935 4575);
PAINT SKYBLUE (-2935 4575);
FORCEPROP 1 LAST MATERIAL CHIP
J 0
(-2935 4525);
DISPLAY 0.489362 (-2935 4525);
PAINT SKYBLUE (-2935 4525);
FORCEPROP 1 LAST PART_NUMBER TMP_QCS31002JB28
J 0
(-2935 4475);
DISPLAY 0.489362 (-2935 4475);
PAINT SKYBLUE (-2935 4475);
FORCEPROP 1 LAST PACK_TYPE 0402LF
J 0
(-2935 4425);
DISPLAY 0.489362 (-2935 4425);
PAINT SKYBLUE (-2935 4425);
FORCEPROP 1 LAST PATH I197
J 0
(-2925 4775);
DISPLAY 0.978723 (-2925 4775);
PAINT WHITE (-2925 4775);
DISPLAY INVISIBLE (-2925 4775);
FORCEPROP 2 LAST CDS_LIB pure_quanta
J 0
(-2975 4600);
DISPLAY INVISIBLE (-2975 4600);
FORCEPROP 2 LAST BOM_COST OCP3.0 
J 0
(-2925 4775);
DISPLAY 0.680851 (-2925 4775);
DISPLAY INVISIBLE (-2925 4775);
FORCEADD MOSFET_N..1
(-3025 4150);
FORCEPROP 1 LAST LOCATION U76
J 0
(-2875 4225);
DISPLAY 0.489362 (-2875 4225);
PAINT SKYBLUE (-2875 4225);
FORCEPROP 0 LAST $SEC 1
J 0
(-2875 4275);
DISPLAY 0.680851 (-2875 4275);
PAINT MONO (-2875 4275);
DISPLAY INVISIBLE (-2875 4275);
FORCEPROP 0 LAST CDS_SEC 1
J 0
(-2875 4275);
DISPLAY 1.021277 (-2875 4275);
DISPLAY INVISIBLE (-2875 4275);
FORCEPROP 1 LASTPIN (-2975 4250) $PN D
R 1
J 0
(-2975 4243);
DISPLAY 0.489362 (-2975 4243);
PAINT MONO (-2975 4243);
FORCEPROP 1 LASTPIN (-3125 4050) $PN G
J 2
(-3115 4053);
DISPLAY 0.489362 (-3115 4053);
PAINT MONO (-3115 4053);
FORCEPROP 1 LASTPIN (-2975 3950) $PN S
R 1
J 2
(-2975 3963);
DISPLAY 0.489362 (-2975 3963);
PAINT MONO (-2975 3963);
FORCEPROP 1 LAST VALUE BSS138K
J 0
(-2900 4100);
DISPLAY 0.489362 (-2900 4100);
PAINT SKYBLUE (-2900 4100);
FORCEPROP 2 LAST PATH I198
J 0
(-2875 4250);
DISPLAY 0.680851 (-2875 4250);
FORCEPROP 1 LAST MATERIAL IC
J 0
(-2903 3981);
DISPLAY 0.489362 (-2903 3981);
PAINT SKYBLUE (-2903 3981);
FORCEPROP 1 LAST PART_NUMBER BAM138K0000
J 0
(-2903 4036);
DISPLAY 0.489362 (-2903 4036);
PAINT SKYBLUE (-2903 4036);
FORCEPROP 1 LAST PACK_TYPE SMLF
J 0
(-3000 3900);
DISPLAY 0.723404 (-3000 3900);
PAINT SKYBLUE (-3000 3900);
DISPLAY INVISIBLE (-3000 3900);
FORCEPROP 2 LAST CDS_LIB pure_quanta
J 0
(-3025 4150);
DISPLAY INVISIBLE (-3025 4150);
FORCEPROP 1 LAST CDS_LMAN_SYM_OUTLINE -50,50,100,-150
J 0
(-3025 4150);
DISPLAY 0.468085 (-3025 4150);
PAINT GREEN (-3025 4150);
DISPLAY INVISIBLE (-3025 4150);
FORCEPROP 0 LAST MANUF_PN BSS138K
J 0
(-2900 4275);
DISPLAY 0.510638 (-2900 4275);
DISPLAY INVISIBLE (-2900 4275);
FORCEADD UNIVERSAL_GND..1
(-2975 3825);
FORCEPROP 3 LASTPIN (-2975 3875) SIG_NAME GND\g
J 0
(-2965 3885);
DISPLAY 0.659574 (-2965 3885);
PAINT MONO (-2965 3885);
DISPLAY INVISIBLE (-2965 3885);
FORCEPROP 2 LAST CDS_LIB pure_quanta_power
J 0
(-2975 3825);
DISPLAY INVISIBLE (-2975 3825);
FORCEPROP 1 LAST PATH I199
J 0
(-2900 3825);
DISPLAY 0.872340 (-2900 3825);
PAINT AQUA (-2900 3825);
DISPLAY INVISIBLE (-2900 3825);
FORCEPROP 1 LAST HDL_POWER GND
J 1
(-2950 3750);
DISPLAY 0.872340 (-2950 3750);
PAINT GREEN (-2950 3750);
DISPLAY INVISIBLE (-2950 3750);
FORCEADD UNIVERSAL_POWER..1
(-6450 1225);
FORCEPROP 3 LASTPIN (-6450 1175) SIG_NAME P1V8_STBY\g
J 0
(-6440 1185);
DISPLAY 0.659574 (-6440 1185);
PAINT MONO (-6440 1185);
DISPLAY INVISIBLE (-6440 1185);
FORCEPROP 1 LAST HDL_POWER P1V8_STBY
J 1
(-6450 1275);
DISPLAY 0.489362 (-6450 1275);
PAINT GREEN (-6450 1275);
FORCEPROP 1 LAST PATH I20
J 0
(-6400 1250);
DISPLAY 0.872340 (-6400 1250);
PAINT AQUA (-6400 1250);
DISPLAY INVISIBLE (-6400 1250);
FORCEPROP 2 LAST CDS_LIB pure_quanta_power
J 0
(-6450 1225);
DISPLAY INVISIBLE (-6450 1225);
FORCEPROP 2 LAST BOM_COST OCP3.0 
J 0
(-6450 1325);
DISPLAY 0.680851 (-6450 1325);
DISPLAY INVISIBLE (-6450 1325);
FORCEADD UNIVERSAL_POWER..1
(-3550 4525);
FORCEPROP 3 LASTPIN (-3550 4475) SIG_NAME P12V_STBY\g
J 0
(-3540 4485);
DISPLAY 0.659574 (-3540 4485);
PAINT MONO (-3540 4485);
DISPLAY INVISIBLE (-3540 4485);
FORCEPROP 1 LAST HDL_POWER P12V_STBY
J 1
(-3550 4575);
DISPLAY 0.489362 (-3550 4575);
PAINT GREEN (-3550 4575);
FORCEPROP 1 LAST PATH I200
J 0
(-3500 4550);
DISPLAY 0.872340 (-3500 4550);
PAINT AQUA (-3500 4550);
DISPLAY INVISIBLE (-3500 4550);
FORCEPROP 2 LAST CDS_LIB pure_quanta_power
J 0
(-3550 4525);
DISPLAY INVISIBLE (-3550 4525);
FORCEPROP 2 LAST BOM_COST OCP3.0 
J 0
(-3550 4625);
DISPLAY 0.680851 (-3550 4625);
DISPLAY INVISIBLE (-3550 4625);
FORCEADD Q_RES..2
(-3550 4300);
FORCEPROP 1 LAST LOCATION R886
J 0
(-3505 4425);
DISPLAY 0.489362 (-3505 4425);
PAINT SKYBLUE (-3505 4425);
FORCEPROP 0 LAST $SEC 1
J 0
(-3500 4475);
DISPLAY 0.680851 (-3500 4475);
PAINT MONO (-3500 4475);
DISPLAY INVISIBLE (-3500 4475);
FORCEPROP 0 LAST CDS_SEC 1
J 0
(-3500 4475);
DISPLAY 1.021277 (-3500 4475);
DISPLAY INVISIBLE (-3500 4475);
FORCEPROP 1 LASTPIN (-3550 4400) $PN 1
J 0
(-3545 4362);
DISPLAY 0.489362 (-3545 4362);
PAINT MONO (-3545 4362);
FORCEPROP 1 LASTPIN (-3550 4200) $PN 2
J 0
(-3545 4210);
DISPLAY 0.489362 (-3545 4210);
PAINT MONO (-3545 4210);
FORCEPROP 1 LAST MATERIAL CHIP
J 0
(-3510 4225);
DISPLAY 0.489362 (-3510 4225);
PAINT SKYBLUE (-3510 4225);
FORCEPROP 1 LAST WATTAGE 1/16W
J 0
(-3510 4275);
DISPLAY 0.489362 (-3510 4275);
PAINT SKYBLUE (-3510 4275);
FORCEPROP 1 LAST TOLERANCE 5%
J 0
(-3505 4325);
DISPLAY 0.489362 (-3505 4325);
PAINT SKYBLUE (-3505 4325);
FORCEPROP 1 LAST VALUE 10K
J 0
(-3505 4375);
DISPLAY 0.489362 (-3505 4375);
PAINT SKYBLUE (-3505 4375);
FORCEPROP 1 LAST PACK_TYPE 0402LF
J 0
(-3510 4125);
DISPLAY 0.489362 (-3510 4125);
PAINT SKYBLUE (-3510 4125);
FORCEPROP 1 LAST PART_NUMBER TMP_QCS31002JB28
J 0
(-3510 4175);
DISPLAY 0.489362 (-3510 4175);
PAINT SKYBLUE (-3510 4175);
FORCEPROP 2 LAST BOM_COST OCP3.0 
J 0
(-3500 4475);
DISPLAY 0.680851 (-3500 4475);
DISPLAY INVISIBLE (-3500 4475);
FORCEPROP 1 LAST PATH I201
J 0
(-3500 4475);
DISPLAY 0.978723 (-3500 4475);
PAINT WHITE (-3500 4475);
DISPLAY INVISIBLE (-3500 4475);
FORCEPROP 2 LAST CDS_LIB pure_quanta
J 0
(-3550 4300);
DISPLAY INVISIBLE (-3550 4300);
FORCEADD OFFPAGE..1
(-3775 4050);
FORCEPROP 2 LAST $XR1 81 
J 0
(-4147 4050);
DISPLAY 0.638298 (-4147 4050);
PAINT MONO (-4147 4050);
FORCEPROP 2 LAST $XR0 117 
J 0
(-4057 4050);
DISPLAY 0.638298 (-4057 4050);
PAINT MONO (-4057 4050);
FORCEPROP 2 LAST PATH I202
J 0
(-4050 4100);
DISPLAY 0.680851 (-4050 4100);
DISPLAY INVISIBLE (-4050 4100);
FORCEPROP 1 LAST COMMENT_BODY TRUE
J 0
(-3650 3950);
DISPLAY 0.872340 (-3650 3950);
PAINT GREEN (-3650 3950);
DISPLAY INVISIBLE (-3650 3950);
FORCEPROP 1 LAST OFFPAGE TRUE
J 0
(-3450 3925);
DISPLAY 0.872340 (-3450 3925);
PAINT GREEN (-3450 3925);
DISPLAY INVISIBLE (-3450 3925);
FORCEPROP 2 LAST CDS_LIB standard
J 0
(-3775 4050);
DISPLAY INVISIBLE (-3775 4050);
FORCEADD Q_RES..2
(-3550 3800);
FORCEPROP 1 LAST LOCATION R5022
J 0
(-3505 3925);
DISPLAY 0.489362 (-3505 3925);
PAINT SKYBLUE (-3505 3925);
FORCEPROP 0 LAST $SEC 1
J 0
(-3500 3950);
DISPLAY 0.680851 (-3500 3950);
PAINT MONO (-3500 3950);
DISPLAY INVISIBLE (-3500 3950);
FORCEPROP 0 LAST CDS_SEC 1
J 0
(-3500 3950);
DISPLAY 0.680851 (-3500 3950);
DISPLAY INVISIBLE (-3500 3950);
FORCEPROP 1 LASTPIN (-3550 3900) $PN 1
J 0
(-3545 3862);
DISPLAY 0.787234 (-3545 3862);
PAINT MONO (-3545 3862);
FORCEPROP 1 LASTPIN (-3550 3700) $PN 2
J 0
(-3545 3710);
DISPLAY 0.787234 (-3545 3710);
PAINT MONO (-3545 3710);
FORCEPROP 1 LAST PACK_TYPE 0402LF
J 0
(-3510 3625);
DISPLAY 0.489362 (-3510 3625);
PAINT SKYBLUE (-3510 3625);
FORCEPROP 1 LAST MATERIAL CHIP
J 0
(-3510 3725);
DISPLAY 0.489362 (-3510 3725);
PAINT SKYBLUE (-3510 3725);
FORCEPROP 1 LAST PART_NUMBER CS23832FB01
J 0
(-3510 3675);
DISPLAY 0.489362 (-3510 3675);
PAINT SKYBLUE (-3510 3675);
FORCEPROP 1 LAST WATTAGE 1/16W
J 0
(-3510 3775);
DISPLAY 0.489362 (-3510 3775);
PAINT SKYBLUE (-3510 3775);
FORCEPROP 1 LAST TOLERANCE 1%
J 0
(-3505 3825);
DISPLAY 0.489362 (-3505 3825);
PAINT SKYBLUE (-3505 3825);
FORCEPROP 1 LAST VALUE 3.83K
J 0
(-3505 3875);
DISPLAY 0.489362 (-3505 3875);
PAINT SKYBLUE (-3505 3875);
FORCEPROP 2 LAST CDS_LIB pure_quanta
J 0
(-3550 3800);
DISPLAY INVISIBLE (-3550 3800);
FORCEPROP 1 LAST PATH I203
J 0
(-3500 3975);
DISPLAY 0.978723 (-3500 3975);
PAINT WHITE (-3500 3975);
DISPLAY INVISIBLE (-3500 3975);
FORCEPROP 2 LAST BOM_COST OCP3.0 
J 0
(-3500 3975);
DISPLAY 0.680851 (-3500 3975);
DISPLAY INVISIBLE (-3500 3975);
FORCEADD UNIVERSAL_GND..1
(-3550 3500);
FORCEPROP 3 LASTPIN (-3550 3550) SIG_NAME GND\g
J 0
(-3540 3560);
DISPLAY 0.659574 (-3540 3560);
PAINT MONO (-3540 3560);
DISPLAY INVISIBLE (-3540 3560);
FORCEPROP 2 LAST CDS_LIB pure_quanta_power
J 0
(-3550 3500);
DISPLAY INVISIBLE (-3550 3500);
FORCEPROP 1 LAST PATH I204
J 0
(-3475 3500);
DISPLAY 0.872340 (-3475 3500);
PAINT AQUA (-3475 3500);
DISPLAY INVISIBLE (-3475 3500);
FORCEPROP 1 LAST HDL_POWER GND
J 1
(-3525 3425);
DISPLAY 0.872340 (-3525 3425);
PAINT GREEN (-3525 3425);
DISPLAY INVISIBLE (-3525 3425);
FORCEADD Q_RES..2
(-2475 4050);
FORCEPROP 1 LAST LOCATION R5023
J 0
(-2430 4175);
DISPLAY 0.489362 (-2430 4175);
PAINT SKYBLUE (-2430 4175);
FORCEPROP 0 LAST $SEC 1
J 0
(-2425 4200);
DISPLAY 0.680851 (-2425 4200);
PAINT MONO (-2425 4200);
DISPLAY INVISIBLE (-2425 4200);
FORCEPROP 0 LAST CDS_SEC 1
J 0
(-2425 4200);
DISPLAY 0.680851 (-2425 4200);
DISPLAY INVISIBLE (-2425 4200);
FORCEPROP 1 LASTPIN (-2475 4150) $PN 1
J 0
(-2470 4112);
DISPLAY 0.787234 (-2470 4112);
PAINT MONO (-2470 4112);
FORCEPROP 1 LASTPIN (-2475 3950) $PN 2
J 0
(-2470 3960);
DISPLAY 0.787234 (-2470 3960);
PAINT MONO (-2470 3960);
FORCEPROP 1 LAST TOLERANCE 1%
J 0
(-2430 4075);
DISPLAY 0.489362 (-2430 4075);
PAINT SKYBLUE (-2430 4075);
FORCEPROP 1 LAST VALUE 3.83K
J 0
(-2430 4125);
DISPLAY 0.489362 (-2430 4125);
PAINT SKYBLUE (-2430 4125);
FORCEPROP 1 LAST PART_NUMBER CS23832FB01
J 0
(-2435 3925);
DISPLAY 0.489362 (-2435 3925);
PAINT SKYBLUE (-2435 3925);
FORCEPROP 1 LAST WATTAGE 1/16W
J 0
(-2435 4025);
DISPLAY 0.489362 (-2435 4025);
PAINT SKYBLUE (-2435 4025);
FORCEPROP 1 LAST MATERIAL CHIP
J 0
(-2435 3975);
DISPLAY 0.489362 (-2435 3975);
PAINT SKYBLUE (-2435 3975);
FORCEPROP 1 LAST PACK_TYPE 0402LF
J 0
(-2435 3875);
DISPLAY 0.489362 (-2435 3875);
PAINT SKYBLUE (-2435 3875);
FORCEPROP 2 LAST BOM_COST OCP3.0 
J 0
(-2425 4225);
DISPLAY 0.680851 (-2425 4225);
DISPLAY INVISIBLE (-2425 4225);
FORCEPROP 1 LAST PATH I205
J 0
(-2425 4225);
DISPLAY 0.978723 (-2425 4225);
PAINT WHITE (-2425 4225);
DISPLAY INVISIBLE (-2425 4225);
FORCEPROP 2 LAST CDS_LIB pure_quanta
J 0
(-2475 4050);
DISPLAY INVISIBLE (-2475 4050);
FORCEADD UNIVERSAL_GND..1
(-2475 3750);
FORCEPROP 3 LASTPIN (-2475 3800) SIG_NAME GND\g
J 0
(-2465 3810);
DISPLAY 0.659574 (-2465 3810);
PAINT MONO (-2465 3810);
DISPLAY INVISIBLE (-2465 3810);
FORCEPROP 1 LAST HDL_POWER GND
J 1
(-2450 3675);
DISPLAY 0.872340 (-2450 3675);
PAINT GREEN (-2450 3675);
DISPLAY INVISIBLE (-2450 3675);
FORCEPROP 1 LAST PATH I206
J 0
(-2400 3750);
DISPLAY 0.872340 (-2400 3750);
PAINT AQUA (-2400 3750);
DISPLAY INVISIBLE (-2400 3750);
FORCEPROP 2 LAST CDS_LIB pure_quanta_power
J 0
(-2475 3750);
DISPLAY INVISIBLE (-2475 3750);
FORCEADD Q_RES..2
(-6450 950);
FORCEPROP 1 LAST LOCATION R1197
J 0
(-6405 1075);
DISPLAY 0.489362 (-6405 1075);
PAINT SKYBLUE (-6405 1075);
FORCEPROP 2 LAST $SEC 1
J 0
(-6400 1175);
DISPLAY 0.680851 (-6400 1175);
PAINT MONO (-6400 1175);
DISPLAY INVISIBLE (-6400 1175);
FORCEPROP 2 LAST CDS_SEC 1
J 0
(-6400 1175);
DISPLAY 0.680851 (-6400 1175);
DISPLAY INVISIBLE (-6400 1175);
FORCEPROP 1 LASTPIN (-6450 1050) $PN 1
J 0
(-6445 1012);
DISPLAY 0.489362 (-6445 1012);
PAINT MONO (-6445 1012);
FORCEPROP 1 LASTPIN (-6450 850) $PN 2
J 0
(-6445 860);
DISPLAY 0.489362 (-6445 860);
PAINT MONO (-6445 860);
FORCEPROP 1 LAST PACK_TYPE 0402LF
J 0
(-6410 775);
DISPLAY 0.489362 (-6410 775);
PAINT SKYBLUE (-6410 775);
FORCEPROP 1 LAST PART_NUMBER TMP_QCS24702JB38
J 0
(-6410 825);
DISPLAY 0.489362 (-6410 825);
PAINT SKYBLUE (-6410 825);
FORCEPROP 1 LAST VALUE 4.7K
J 0
(-6405 1025);
DISPLAY 0.489362 (-6405 1025);
PAINT SKYBLUE (-6405 1025);
FORCEPROP 1 LAST TOLERANCE 5%
J 0
(-6405 975);
DISPLAY 0.489362 (-6405 975);
PAINT SKYBLUE (-6405 975);
FORCEPROP 1 LAST MATERIAL CHIP
J 0
(-6410 875);
DISPLAY 0.489362 (-6410 875);
PAINT SKYBLUE (-6410 875);
FORCEPROP 1 LAST WATTAGE 1/16W
J 0
(-6410 925);
DISPLAY 0.489362 (-6410 925);
PAINT SKYBLUE (-6410 925);
FORCEPROP 1 LAST PATH I21
J 0
(-6400 1125);
DISPLAY 0.978723 (-6400 1125);
PAINT WHITE (-6400 1125);
DISPLAY INVISIBLE (-6400 1125);
FORCEPROP 2 LAST BOM_COST OCP3.0 
J 0
(-6400 1125);
DISPLAY 0.680851 (-6400 1125);
DISPLAY INVISIBLE (-6400 1125);
FORCEPROP 2 LAST CDS_LIB pure_quanta
J 0
(-6450 950);
DISPLAY INVISIBLE (-6450 950);
FORCEADD Q_RES..1
(-5925 700);
FORCEPROP 1 LAST LOCATION R1365
J 0
(-6275 700);
DISPLAY 0.489362 (-6275 700);
PAINT SKYBLUE (-6275 700);
FORCEPROP 2 LAST $SEC 1
J 0
(-5975 900);
DISPLAY 0.680851 (-5975 900);
PAINT MONO (-5975 900);
DISPLAY INVISIBLE (-5975 900);
FORCEPROP 2 LAST CDS_SEC 1
J 0
(-5975 900);
DISPLAY 0.680851 (-5975 900);
DISPLAY INVISIBLE (-5975 900);
FORCEPROP 1 LASTPIN (-6025 700) $PN 1
J 0
(-6013 712);
DISPLAY 0.489362 (-6013 712);
PAINT MONO (-6013 712);
FORCEPROP 1 LASTPIN (-5825 700) $PN 2
J 0
(-5863 712);
DISPLAY 0.489362 (-5863 712);
PAINT MONO (-5863 712);
FORCEPROP 1 LAST VALUE 33
J 2
(-5725 700);
DISPLAY 0.489362 (-5725 700);
PAINT SKYBLUE (-5725 700);
FORCEPROP 1 LAST MATERIAL CHIP
J 0
(-5675 700);
DISPLAY 0.489362 (-5675 700);
PAINT SKYBLUE (-5675 700);
FORCEPROP 1 LAST PACK_TYPE 0402LF
J 0
(-5850 650);
DISPLAY 0.489362 (-5850 650);
PAINT SKYBLUE (-5850 650);
DISPLAY INVISIBLE (-5850 650);
FORCEPROP 1 LAST PART_NUMBER CS03302JB29
J 0
(-5850 750);
DISPLAY 0.489362 (-5850 750);
PAINT SKYBLUE (-5850 750);
DISPLAY INVISIBLE (-5850 750);
FORCEPROP 1 LAST TOLERANCE 5%
J 0
(-5925 650);
DISPLAY 0.489362 (-5925 650);
PAINT SKYBLUE (-5925 650);
DISPLAY INVISIBLE (-5925 650);
FORCEPROP 1 LAST WATTAGE 1/16W
J 2
(-5950 600);
DISPLAY 0.489362 (-5950 600);
PAINT SKYBLUE (-5950 600);
DISPLAY INVISIBLE (-5950 600);
FORCEPROP 1 LAST PATH I22
J 0
(-5975 850);
DISPLAY 0.978723 (-5975 850);
PAINT WHITE (-5975 850);
DISPLAY INVISIBLE (-5975 850);
FORCEPROP 2 LAST CDS_LIB pure_quanta
J 0
(-5925 700);
DISPLAY INVISIBLE (-5925 700);
FORCEPROP 2 LAST BOM_COST OCP3.0 
J 0
(-5850 800);
DISPLAY 0.680851 (-5850 800);
DISPLAY INVISIBLE (-5850 800);
FORCEADD SN74LVC1G07DBVR..1
(-7250 1525);
FORCEPROP 1 LAST LOCATION U111
J 0
(-7375 1780);
DISPLAY 0.489362 (-7375 1780);
PAINT SKYBLUE (-7375 1780);
FORCEPROP 2 LAST $SEC 1
J 0
(-7375 1925);
DISPLAY 0.680851 (-7375 1925);
PAINT MONO (-7375 1925);
DISPLAY INVISIBLE (-7375 1925);
FORCEPROP 2 LAST CDS_SEC 1
J 0
(-7375 1925);
DISPLAY 0.680851 (-7375 1925);
DISPLAY INVISIBLE (-7375 1925);
FORCEPROP 2 LASTPIN (-7425 1525) $PN 2
J 2
(-7435 1535);
DISPLAY 0.489362 (-7435 1535);
PAINT MONO (-7435 1535);
FORCEPROP 2 LASTPIN (-7425 1425) $PN 3
J 2
(-7435 1435);
DISPLAY 0.489362 (-7435 1435);
PAINT MONO (-7435 1435);
FORCEPROP 2 LASTPIN (-7075 1425) $PN 1
J 0
(-7065 1435);
DISPLAY 0.489362 (-7065 1435);
PAINT MONO (-7065 1435);
FORCEPROP 2 LASTPIN (-7425 1625) $PN 5
J 2
(-7435 1635);
DISPLAY 0.489362 (-7435 1635);
PAINT MONO (-7435 1635);
FORCEPROP 2 LASTPIN (-7075 1525) $PN 4
J 0
(-7065 1535);
DISPLAY 0.489362 (-7065 1535);
PAINT MONO (-7065 1535);
FORCEPROP 2 LAST PACK_TYPE SMLF
J 0
(-7375 1825);
DISPLAY 0.489362 (-7375 1825);
PAINT SKYBLUE (-7375 1825);
FORCEPROP 1 LAST PART_NUMBER AL1G0007024
J 0
(-7375 1735);
DISPLAY 0.489362 (-7375 1735);
PAINT SKYBLUE (-7375 1735);
FORCEPROP 2 LAST VALUE SN74LVC1G07DBVR
J 0
(-7375 1875);
DISPLAY 0.489362 (-7375 1875);
PAINT SKYBLUE (-7375 1875);
FORCEPROP 1 LAST MATERIAL IC
J 0
(-7375 1685);
DISPLAY 0.489362 (-7375 1685);
PAINT SKYBLUE (-7375 1685);
FORCEPROP 1 LAST PATH I23
J 0
(-7150 1680);
DISPLAY 0.723404 (-7150 1680);
PAINT GREEN (-7150 1680);
DISPLAY INVISIBLE (-7150 1680);
FORCEPROP 2 LAST CDS_LIB pure_quanta
J 0
(-7250 1525);
DISPLAY INVISIBLE (-7250 1525);
FORCEPROP 1 LAST NEEDS_NO_SIZE TRUE
J 0
(-7250 1525);
DISPLAY 0.468085 (-7250 1525);
PAINT GREEN (-7250 1525);
DISPLAY INVISIBLE (-7250 1525);
FORCEADD UNIVERSAL_GND..1
(-7550 1225);
FORCEPROP 3 LASTPIN (-7550 1275) SIG_NAME GND\g
J 0
(-7540 1285);
DISPLAY 0.659574 (-7540 1285);
PAINT MONO (-7540 1285);
DISPLAY INVISIBLE (-7540 1285);
FORCEPROP 1 LAST HDL_POWER GND
J 1
(-7525 1150);
DISPLAY 0.872340 (-7525 1150);
PAINT GREEN (-7525 1150);
DISPLAY INVISIBLE (-7525 1150);
FORCEPROP 1 LAST PATH I24
J 0
(-7475 1225);
DISPLAY 0.872340 (-7475 1225);
PAINT AQUA (-7475 1225);
DISPLAY INVISIBLE (-7475 1225);
FORCEPROP 2 LAST BOM_COST OCP3.0 
J 0
(-7750 1300);
DISPLAY 0.680851 (-7750 1300);
DISPLAY INVISIBLE (-7750 1300);
FORCEPROP 2 LAST CDS_LIB pure_quanta_power
J 0
(-7550 1225);
DISPLAY INVISIBLE (-7550 1225);
FORCEADD SN74LVC1G07DBVR..1
(-7250 700);
FORCEPROP 1 LAST LOCATION U112
J 0
(-7375 955);
DISPLAY 0.489362 (-7375 955);
PAINT SKYBLUE (-7375 955);
FORCEPROP 2 LAST $SEC 1
J 0
(-7375 1100);
DISPLAY 0.680851 (-7375 1100);
PAINT MONO (-7375 1100);
DISPLAY INVISIBLE (-7375 1100);
FORCEPROP 2 LAST CDS_SEC 1
J 0
(-7375 1100);
DISPLAY 0.680851 (-7375 1100);
DISPLAY INVISIBLE (-7375 1100);
FORCEPROP 2 LASTPIN (-7425 700) $PN 2
J 2
(-7435 710);
DISPLAY 0.489362 (-7435 710);
PAINT MONO (-7435 710);
FORCEPROP 2 LASTPIN (-7425 600) $PN 3
J 2
(-7435 610);
DISPLAY 0.489362 (-7435 610);
PAINT MONO (-7435 610);
FORCEPROP 2 LASTPIN (-7075 600) $PN 1
J 0
(-7065 610);
DISPLAY 0.489362 (-7065 610);
PAINT MONO (-7065 610);
FORCEPROP 2 LASTPIN (-7425 800) $PN 5
J 2
(-7435 810);
DISPLAY 0.489362 (-7435 810);
PAINT MONO (-7435 810);
FORCEPROP 2 LASTPIN (-7075 700) $PN 4
J 0
(-7065 710);
DISPLAY 0.489362 (-7065 710);
PAINT MONO (-7065 710);
FORCEPROP 2 LAST PACK_TYPE SMLF
J 0
(-7375 1000);
DISPLAY 0.489362 (-7375 1000);
PAINT SKYBLUE (-7375 1000);
FORCEPROP 1 LAST PART_NUMBER AL1G0007024
J 0
(-7375 910);
DISPLAY 0.489362 (-7375 910);
PAINT SKYBLUE (-7375 910);
FORCEPROP 2 LAST VALUE SN74LVC1G07DBVR
J 0
(-7375 1050);
DISPLAY 0.489362 (-7375 1050);
PAINT SKYBLUE (-7375 1050);
FORCEPROP 1 LAST MATERIAL IC
J 0
(-7375 860);
DISPLAY 0.489362 (-7375 860);
PAINT SKYBLUE (-7375 860);
FORCEPROP 1 LAST PATH I25
J 0
(-7150 855);
DISPLAY 0.723404 (-7150 855);
PAINT GREEN (-7150 855);
DISPLAY INVISIBLE (-7150 855);
FORCEPROP 2 LAST CDS_LIB pure_quanta
J 0
(-7250 700);
DISPLAY INVISIBLE (-7250 700);
FORCEPROP 1 LAST NEEDS_NO_SIZE TRUE
J 0
(-7250 700);
DISPLAY 0.468085 (-7250 700);
PAINT GREEN (-7250 700);
DISPLAY INVISIBLE (-7250 700);
FORCEADD UNIVERSAL_POWER..1
(-7900 2025);
FORCEPROP 3 LASTPIN (-7900 1975) SIG_NAME P3V3_STBY\g
J 0
(-7890 1985);
DISPLAY 0.659574 (-7890 1985);
PAINT MONO (-7890 1985);
DISPLAY INVISIBLE (-7890 1985);
FORCEPROP 1 LAST HDL_POWER P3V3_STBY
J 1
(-7900 2075);
DISPLAY 0.489362 (-7900 2075);
PAINT GREEN (-7900 2075);
FORCEPROP 1 LAST PATH I26
J 0
(-7850 2050);
DISPLAY 0.872340 (-7850 2050);
PAINT AQUA (-7850 2050);
DISPLAY INVISIBLE (-7850 2050);
FORCEPROP 2 LAST BOM_COST OCP3.0 
J 0
(-7900 2125);
DISPLAY 0.680851 (-7900 2125);
DISPLAY INVISIBLE (-7900 2125);
FORCEPROP 2 LAST CDS_LIB pure_quanta_power
J 0
(-7900 2025);
DISPLAY INVISIBLE (-7900 2025);
FORCEADD UNIVERSAL_GND..1
(-7900 1575);
FORCEPROP 3 LASTPIN (-7900 1625) SIG_NAME GND\g
J 0
(-7890 1635);
DISPLAY 0.659574 (-7890 1635);
PAINT MONO (-7890 1635);
DISPLAY INVISIBLE (-7890 1635);
FORCEPROP 1 LAST HDL_POWER GND
J 1
(-7875 1500);
DISPLAY 0.872340 (-7875 1500);
PAINT GREEN (-7875 1500);
DISPLAY INVISIBLE (-7875 1500);
FORCEPROP 1 LAST PATH I27
J 0
(-7825 1575);
DISPLAY 0.872340 (-7825 1575);
PAINT AQUA (-7825 1575);
DISPLAY INVISIBLE (-7825 1575);
FORCEPROP 2 LAST CDS_LIB pure_quanta_power
J 0
(-7900 1575);
DISPLAY INVISIBLE (-7900 1575);
FORCEPROP 2 LAST BOM_COST OCP3.0 
J 0
(-8100 1650);
DISPLAY 0.680851 (-8100 1650);
DISPLAY INVISIBLE (-8100 1650);
FORCEADD Q_CAP..1
(-7900 1775);
FORCEPROP 1 LAST LOCATION C584
J 0
(-7825 1900);
DISPLAY 0.489362 (-7825 1900);
PAINT SKYBLUE (-7825 1900);
FORCEPROP 2 LAST $SEC 1
J 0
(-7850 1975);
DISPLAY 0.680851 (-7850 1975);
PAINT MONO (-7850 1975);
DISPLAY INVISIBLE (-7850 1975);
FORCEPROP 2 LAST CDS_SEC 1
J 0
(-7850 1975);
DISPLAY 0.680851 (-7850 1975);
DISPLAY INVISIBLE (-7850 1975);
FORCEPROP 1 LASTPIN (-7900 1875) $PN 1
J 0
(-7890 1855);
DISPLAY 0.489362 (-7890 1855);
FORCEPROP 1 LASTPIN (-7900 1675) $PN 2
J 0
(-7890 1655);
DISPLAY 0.489362 (-7890 1655);
FORCEPROP 1 LAST PACK_TYPE 0402
J 0
(-7825 1600);
DISPLAY 0.489362 (-7825 1600);
PAINT SKYBLUE (-7825 1600);
FORCEPROP 1 LAST VOLTAGE 25V
J 0
(-7825 1800);
DISPLAY 0.489362 (-7825 1800);
PAINT SKYBLUE (-7825 1800);
FORCEPROP 1 LAST PART_NUMBER CH4104K1B00
J 0
(-7825 1650);
DISPLAY 0.489362 (-7825 1650);
PAINT SKYBLUE (-7825 1650);
FORCEPROP 1 LAST VALUE 0.1UF
J 0
(-7825 1850);
DISPLAY 0.489362 (-7825 1850);
PAINT SKYBLUE (-7825 1850);
FORCEPROP 1 LAST TOLERANCE 10%
J 0
(-7825 1750);
DISPLAY 0.489362 (-7825 1750);
PAINT SKYBLUE (-7825 1750);
FORCEPROP 1 LAST MATERIAL X7R
J 0
(-7825 1700);
DISPLAY 0.489362 (-7825 1700);
PAINT SKYBLUE (-7825 1700);
FORCEPROP 1 LAST PATH I28
J 0
(-7850 1925);
DISPLAY 0.978723 (-7850 1925);
PAINT WHITE (-7850 1925);
DISPLAY INVISIBLE (-7850 1925);
FORCEPROP 2 LAST BOM_COST OCP3.0 
J 0
(-7875 1900);
DISPLAY 0.680851 (-7875 1900);
DISPLAY INVISIBLE (-7875 1900);
FORCEPROP 2 LAST CDS_LIB pure_quanta
J 0
(-7900 1775);
DISPLAY INVISIBLE (-7900 1775);
FORCEADD UNIVERSAL_POWER..1
(-7900 1200);
FORCEPROP 3 LASTPIN (-7900 1150) SIG_NAME P3V3_STBY\g
J 0
(-7890 1160);
DISPLAY 0.659574 (-7890 1160);
PAINT MONO (-7890 1160);
DISPLAY INVISIBLE (-7890 1160);
FORCEPROP 1 LAST HDL_POWER P3V3_STBY
J 1
(-7900 1250);
DISPLAY 0.489362 (-7900 1250);
PAINT GREEN (-7900 1250);
FORCEPROP 1 LAST PATH I30
J 0
(-7850 1225);
DISPLAY 0.872340 (-7850 1225);
PAINT AQUA (-7850 1225);
DISPLAY INVISIBLE (-7850 1225);
FORCEPROP 2 LAST CDS_LIB pure_quanta_power
J 0
(-7900 1200);
DISPLAY INVISIBLE (-7900 1200);
FORCEPROP 2 LAST BOM_COST OCP3.0 
J 0
(-7900 1300);
DISPLAY 0.680851 (-7900 1300);
DISPLAY INVISIBLE (-7900 1300);
FORCEADD Q_CAP..1
(-7900 950);
FORCEPROP 1 LAST LOCATION C667
J 0
(-7825 1075);
DISPLAY 0.489362 (-7825 1075);
PAINT SKYBLUE (-7825 1075);
FORCEPROP 2 LAST $SEC 1
J 0
(-7850 1150);
DISPLAY 0.680851 (-7850 1150);
PAINT MONO (-7850 1150);
DISPLAY INVISIBLE (-7850 1150);
FORCEPROP 2 LAST CDS_SEC 1
J 0
(-7850 1150);
DISPLAY 0.680851 (-7850 1150);
DISPLAY INVISIBLE (-7850 1150);
FORCEPROP 1 LASTPIN (-7900 1050) $PN 1
J 0
(-7890 1030);
DISPLAY 0.489362 (-7890 1030);
FORCEPROP 1 LASTPIN (-7900 850) $PN 2
J 0
(-7890 830);
DISPLAY 0.489362 (-7890 830);
FORCEPROP 1 LAST PACK_TYPE 0402
J 0
(-7825 775);
DISPLAY 0.489362 (-7825 775);
PAINT SKYBLUE (-7825 775);
FORCEPROP 1 LAST VOLTAGE 25V
J 0
(-7825 975);
DISPLAY 0.489362 (-7825 975);
PAINT SKYBLUE (-7825 975);
FORCEPROP 1 LAST PART_NUMBER CH4104K1B00
J 0
(-7825 825);
DISPLAY 0.489362 (-7825 825);
PAINT SKYBLUE (-7825 825);
FORCEPROP 1 LAST VALUE 0.1UF
J 0
(-7825 1025);
DISPLAY 0.489362 (-7825 1025);
PAINT SKYBLUE (-7825 1025);
FORCEPROP 1 LAST TOLERANCE 10%
J 0
(-7825 925);
DISPLAY 0.489362 (-7825 925);
PAINT SKYBLUE (-7825 925);
FORCEPROP 1 LAST MATERIAL X7R
J 0
(-7825 875);
DISPLAY 0.489362 (-7825 875);
PAINT SKYBLUE (-7825 875);
FORCEPROP 1 LAST PATH I31
J 0
(-7850 1100);
DISPLAY 0.978723 (-7850 1100);
PAINT WHITE (-7850 1100);
DISPLAY INVISIBLE (-7850 1100);
FORCEPROP 2 LAST BOM_COST OCP3.0 
J 0
(-7875 1075);
DISPLAY 0.680851 (-7875 1075);
DISPLAY INVISIBLE (-7875 1075);
FORCEPROP 2 LAST CDS_LIB pure_quanta
J 0
(-7900 950);
DISPLAY INVISIBLE (-7900 950);
FORCEADD UNIVERSAL_GND..1
(-7900 750);
FORCEPROP 3 LASTPIN (-7900 800) SIG_NAME GND\g
J 0
(-7890 810);
DISPLAY 0.659574 (-7890 810);
PAINT MONO (-7890 810);
DISPLAY INVISIBLE (-7890 810);
FORCEPROP 1 LAST HDL_POWER GND
J 1
(-7875 675);
DISPLAY 0.872340 (-7875 675);
PAINT GREEN (-7875 675);
DISPLAY INVISIBLE (-7875 675);
FORCEPROP 1 LAST PATH I32
J 0
(-7825 750);
DISPLAY 0.872340 (-7825 750);
PAINT AQUA (-7825 750);
DISPLAY INVISIBLE (-7825 750);
FORCEPROP 2 LAST CDS_LIB pure_quanta_power
J 0
(-7900 750);
DISPLAY INVISIBLE (-7900 750);
FORCEPROP 2 LAST BOM_COST OCP3.0 
J 0
(-8100 825);
DISPLAY 0.680851 (-8100 825);
DISPLAY INVISIBLE (-8100 825);
FORCEADD OFFPAGE..1
(-8725 1525);
FORCEPROP 2 LAST $XR0 152 
J 0
(-9007 1525);
DISPLAY 0.638298 (-9007 1525);
PAINT MONO (-9007 1525);
FORCEPROP 2 LAST PATH I34
J 0
(-8675 1600);
DISPLAY 0.680851 (-8675 1600);
DISPLAY INVISIBLE (-8675 1600);
FORCEPROP 1 LAST COMMENT_BODY TRUE
J 0
(-8600 1425);
DISPLAY 0.872340 (-8600 1425);
PAINT GREEN (-8600 1425);
DISPLAY INVISIBLE (-8600 1425);
FORCEPROP 1 LAST OFFPAGE TRUE
J 0
(-8400 1400);
DISPLAY 0.872340 (-8400 1400);
PAINT GREEN (-8400 1400);
DISPLAY INVISIBLE (-8400 1400);
FORCEPROP 2 LAST CDS_LIB standard
J 0
(-8725 1525);
DISPLAY INVISIBLE (-8725 1525);
FORCEADD OFFPAGE..1
(-8725 700);
FORCEPROP 2 LAST $XR0 152 
J 0
(-9007 700);
DISPLAY 0.638298 (-9007 700);
PAINT MONO (-9007 700);
FORCEPROP 2 LAST PATH I35
J 0
(-8675 775);
DISPLAY 0.680851 (-8675 775);
DISPLAY INVISIBLE (-8675 775);
FORCEPROP 1 LAST COMMENT_BODY TRUE
J 0
(-8600 600);
DISPLAY 0.872340 (-8600 600);
PAINT GREEN (-8600 600);
DISPLAY INVISIBLE (-8600 600);
FORCEPROP 1 LAST OFFPAGE TRUE
J 0
(-8400 575);
DISPLAY 0.872340 (-8400 575);
PAINT GREEN (-8400 575);
DISPLAY INVISIBLE (-8400 575);
FORCEPROP 2 LAST CDS_LIB standard
J 0
(-8725 700);
DISPLAY INVISIBLE (-8725 700);
FORCEADD UNIVERSAL_GND..1
(-7550 400);
FORCEPROP 3 LASTPIN (-7550 450) SIG_NAME GND\g
J 0
(-7540 460);
DISPLAY 0.659574 (-7540 460);
PAINT MONO (-7540 460);
DISPLAY INVISIBLE (-7540 460);
FORCEPROP 1 LAST HDL_POWER GND
J 1
(-7525 325);
DISPLAY 0.872340 (-7525 325);
PAINT GREEN (-7525 325);
DISPLAY INVISIBLE (-7525 325);
FORCEPROP 1 LAST PATH I36
J 0
(-7475 400);
DISPLAY 0.872340 (-7475 400);
PAINT AQUA (-7475 400);
DISPLAY INVISIBLE (-7475 400);
FORCEPROP 2 LAST BOM_COST OCP3.0 
J 0
(-7750 475);
DISPLAY 0.680851 (-7750 475);
DISPLAY INVISIBLE (-7750 475);
FORCEPROP 2 LAST CDS_LIB pure_quanta_power
J 0
(-7550 400);
DISPLAY INVISIBLE (-7550 400);
FORCEADD UNIVERSAL_POWER..1
(-2975 3200);
FORCEPROP 3 LASTPIN (-2975 3150) SIG_NAME P3V3_STBY\g
J 0
(-2965 3160);
DISPLAY 0.659574 (-2965 3160);
PAINT MONO (-2965 3160);
DISPLAY INVISIBLE (-2965 3160);
FORCEPROP 1 LAST HDL_POWER P3V3_STBY
J 1
(-2975 3250);
DISPLAY 0.489362 (-2975 3250);
PAINT GREEN (-2975 3250);
FORCEPROP 1 LAST PATH I37
J 0
(-2925 3225);
DISPLAY 0.872340 (-2925 3225);
PAINT AQUA (-2925 3225);
DISPLAY INVISIBLE (-2925 3225);
FORCEPROP 2 LAST CDS_LIB pure_quanta_power
J 0
(-2975 3200);
DISPLAY INVISIBLE (-2975 3200);
FORCEADD Q_RES..2
(-2975 2925);
FORCEPROP 1 LAST LOCATION R1367
J 0
(-2930 3050);
DISPLAY 0.489362 (-2930 3050);
PAINT SKYBLUE (-2930 3050);
FORCEPROP 2 LAST $SEC 1
J 0
(-2925 3150);
DISPLAY 0.680851 (-2925 3150);
PAINT MONO (-2925 3150);
DISPLAY INVISIBLE (-2925 3150);
FORCEPROP 2 LAST CDS_SEC 1
J 0
(-2925 3150);
DISPLAY 0.680851 (-2925 3150);
DISPLAY INVISIBLE (-2925 3150);
FORCEPROP 1 LASTPIN (-2975 3025) $PN 1
J 0
(-2970 2987);
DISPLAY 0.489362 (-2970 2987);
PAINT MONO (-2970 2987);
FORCEPROP 1 LASTPIN (-2975 2825) $PN 2
J 0
(-2970 2835);
DISPLAY 0.489362 (-2970 2835);
PAINT MONO (-2970 2835);
FORCEPROP 1 LAST PACK_TYPE 0402LF
J 0
(-2935 2800);
DISPLAY 0.489362 (-2935 2800);
PAINT SKYBLUE (-2935 2800);
FORCEPROP 1 LAST VALUE 1K
J 0
(-2930 3000);
DISPLAY 0.489362 (-2930 3000);
PAINT SKYBLUE (-2930 3000);
FORCEPROP 1 LAST TOLERANCE 5%
J 0
(-2930 2950);
DISPLAY 0.489362 (-2930 2950);
PAINT SKYBLUE (-2930 2950);
FORCEPROP 1 LAST MATERIAL CHIP
J 0
(-2935 2850);
DISPLAY 0.489362 (-2935 2850);
PAINT SKYBLUE (-2935 2850);
FORCEPROP 1 LAST WATTAGE 1/16W
J 0
(-2935 2900);
DISPLAY 0.489362 (-2935 2900);
PAINT SKYBLUE (-2935 2900);
FORCEPROP 1 LAST PART_NUMBER TMP_QCS21002JB34
J 0
(-2935 2750);
DISPLAY 0.638298 (-2935 2750);
PAINT SKYBLUE (-2935 2750);
DISPLAY INVISIBLE (-2935 2750);
FORCEPROP 1 LAST PATH I39
J 0
(-2925 3100);
DISPLAY 0.978723 (-2925 3100);
PAINT WHITE (-2925 3100);
DISPLAY INVISIBLE (-2925 3100);
FORCEPROP 2 LAST CDS_LIB pure_quanta
J 0
(-2975 2925);
DISPLAY INVISIBLE (-2975 2925);
FORCEADD MOSFET_N_GSD..1
(-3000 2500);
FORCEPROP 1 LAST LOCATION Q13
J 0
(-2899 2545);
DISPLAY 0.489362 (-2899 2545);
PAINT SKYBLUE (-2899 2545);
FORCEPROP 2 LAST $SEC 1
J 0
(-2900 2725);
DISPLAY 0.680851 (-2900 2725);
PAINT MONO (-2900 2725);
DISPLAY INVISIBLE (-2900 2725);
FORCEPROP 2 LAST CDS_SEC 1
J 0
(-2900 2725);
DISPLAY 0.680851 (-2900 2725);
DISPLAY INVISIBLE (-2900 2725);
FORCEPROP 2 LASTPIN (-2975 2650) $PN D
R 1
J 0
(-2985 2660);
DISPLAY 0.489362 (-2985 2660);
PAINT MONO (-2985 2660);
FORCEPROP 2 LASTPIN (-3175 2450) $PN G
J 2
(-3185 2460);
DISPLAY 0.489362 (-3185 2460);
PAINT MONO (-3185 2460);
FORCEPROP 2 LASTPIN (-2975 2350) $PN S
R 1
J 2
(-2985 2340);
DISPLAY 0.489362 (-2985 2340);
PAINT MONO (-2985 2340);
FORCEPROP 1 LAST PART_NUMBER BAM01380023
J 0
(-2899 2480);
DISPLAY 0.489362 (-2899 2480);
PAINT SKYBLUE (-2899 2480);
FORCEPROP 2 LAST VALUE NX138BK
J 0
(-2900 2625);
DISPLAY 0.489362 (-2900 2625);
PAINT SKYBLUE (-2900 2625);
FORCEPROP 1 LAST MATERIAL IC
J 0
(-2899 2400);
DISPLAY 0.489362 (-2899 2400);
PAINT SKYBLUE (-2899 2400);
FORCEPROP 2 LAST PART_TYPE SMLF
J 0
(-2900 2675);
DISPLAY 1.021277 (-2900 2675);
FORCEPROP 1 LAST PATH I40
J 0
(-3000 2500);
DISPLAY 0.723404 (-3000 2500);
PAINT GREEN (-3000 2500);
DISPLAY INVISIBLE (-3000 2500);
FORCEPROP 1 LAST NEEDS_NO_SIZE TRUE
J 0
(-3000 2500);
DISPLAY 0.468085 (-3000 2500);
PAINT GREEN (-3000 2500);
DISPLAY INVISIBLE (-3000 2500);
FORCEPROP 1 LAST CDS_LMAN_SYM_OUTLINE -100,100,100,-100
J 0
(-3000 2500);
DISPLAY 0.468085 (-3000 2500);
PAINT GREEN (-3000 2500);
DISPLAY INVISIBLE (-3000 2500);
FORCEPROP 2 LAST CDS_LIB pure_quanta
J 0
(-3000 2500);
DISPLAY INVISIBLE (-3000 2500);
FORCEADD Q_RES..1
R 1
(-3350 2225);
FORCEPROP 1 LAST LOCATION R1366
J 0
(-3300 2400);
DISPLAY 0.489362 (-3300 2400);
PAINT SKYBLUE (-3300 2400);
FORCEPROP 2 LAST $SEC 1
R 1
J 0
(-3550 2175);
DISPLAY 0.680851 (-3550 2175);
PAINT MONO (-3550 2175);
DISPLAY INVISIBLE (-3550 2175);
FORCEPROP 2 LAST CDS_SEC 1
R 1
J 0
(-3550 2175);
DISPLAY 1.021277 (-3550 2175);
DISPLAY INVISIBLE (-3550 2175);
FORCEPROP 1 LASTPIN (-3350 2125) $PN 1
R 1
J 0
(-3362 2137);
DISPLAY 0.489362 (-3362 2137);
FORCEPROP 1 LASTPIN (-3350 2325) $PN 2
R 1
J 0
(-3362 2287);
DISPLAY 0.489362 (-3362 2287);
FORCEPROP 1 LAST PACK_TYPE 0402LF
J 0
(-3300 2150);
DISPLAY 0.489362 (-3300 2150);
PAINT SKYBLUE (-3300 2150);
FORCEPROP 1 LAST VALUE 100K
J 2
(-3200 2300);
DISPLAY 0.489362 (-3200 2300);
PAINT SKYBLUE (-3200 2300);
FORCEPROP 1 LAST TOLERANCE 1%
J 0
(-3300 2350);
DISPLAY 0.489362 (-3300 2350);
PAINT SKYBLUE (-3300 2350);
FORCEPROP 1 LAST MATERIAL CHIP
J 0
(-3300 2200);
DISPLAY 0.489362 (-3300 2200);
PAINT SKYBLUE (-3300 2200);
FORCEPROP 1 LAST WATTAGE 1/16W
J 2
(-3175 2250);
DISPLAY 0.489362 (-3175 2250);
PAINT SKYBLUE (-3175 2250);
FORCEPROP 1 LAST PART_NUMBER TMP_QCS41002FB28
J 0
(-3325 2075);
DISPLAY 0.489362 (-3325 2075);
PAINT SKYBLUE (-3325 2075);
DISPLAY INVISIBLE (-3325 2075);
FORCEPROP 1 LAST PATH I41
R 1
J 0
(-3500 2175);
DISPLAY 0.978723 (-3500 2175);
PAINT WHITE (-3500 2175);
DISPLAY INVISIBLE (-3500 2175);
FORCEPROP 2 LAST CDS_LIB pure_quanta
R 1
J 0
(-3350 2225);
PAINT MONO (-3350 2225);
DISPLAY INVISIBLE (-3350 2225);
FORCEADD OFFPAGE..1
(-3900 2450);
FORCEPROP 2 LAST $XR0 80 
J 0
(-4121 2450);
DISPLAY 0.638298 (-4121 2450);
PAINT MONO (-4121 2450);
FORCEPROP 2 LAST PATH I42
J 0
(-3850 2525);
DISPLAY 0.680851 (-3850 2525);
DISPLAY INVISIBLE (-3850 2525);
FORCEPROP 1 LAST COMMENT_BODY TRUE
J 0
(-3775 2350);
DISPLAY 0.872340 (-3775 2350);
PAINT GREEN (-3775 2350);
DISPLAY INVISIBLE (-3775 2350);
FORCEPROP 1 LAST OFFPAGE TRUE
J 0
(-3575 2325);
DISPLAY 0.872340 (-3575 2325);
PAINT GREEN (-3575 2325);
DISPLAY INVISIBLE (-3575 2325);
FORCEPROP 2 LAST CDS_LIB standard
J 0
(-3900 2450);
DISPLAY INVISIBLE (-3900 2450);
FORCEADD Q_RES..2
(-2950 1525);
FORCEPROP 1 LAST LOCATION R1368
J 0
(-2905 1650);
DISPLAY 0.489362 (-2905 1650);
PAINT SKYBLUE (-2905 1650);
FORCEPROP 2 LAST $SEC 1
J 0
(-2900 1750);
DISPLAY 0.680851 (-2900 1750);
PAINT MONO (-2900 1750);
DISPLAY INVISIBLE (-2900 1750);
FORCEPROP 2 LAST CDS_SEC 1
J 0
(-2900 1750);
DISPLAY 0.680851 (-2900 1750);
DISPLAY INVISIBLE (-2900 1750);
FORCEPROP 1 LASTPIN (-2950 1625) $PN 1
J 0
(-2945 1587);
DISPLAY 0.489362 (-2945 1587);
PAINT MONO (-2945 1587);
FORCEPROP 1 LASTPIN (-2950 1425) $PN 2
J 0
(-2945 1435);
DISPLAY 0.489362 (-2945 1435);
PAINT MONO (-2945 1435);
FORCEPROP 1 LAST PACK_TYPE 0402LF
J 0
(-2910 1400);
DISPLAY 0.489362 (-2910 1400);
PAINT SKYBLUE (-2910 1400);
FORCEPROP 1 LAST VALUE 1K
J 0
(-2905 1600);
DISPLAY 0.489362 (-2905 1600);
PAINT SKYBLUE (-2905 1600);
FORCEPROP 1 LAST TOLERANCE 5%
J 0
(-2905 1550);
DISPLAY 0.489362 (-2905 1550);
PAINT SKYBLUE (-2905 1550);
FORCEPROP 1 LAST MATERIAL CHIP
J 0
(-2910 1450);
DISPLAY 0.489362 (-2910 1450);
PAINT SKYBLUE (-2910 1450);
FORCEPROP 1 LAST WATTAGE 1/16W
J 0
(-2910 1500);
DISPLAY 0.489362 (-2910 1500);
PAINT SKYBLUE (-2910 1500);
FORCEPROP 1 LAST PART_NUMBER TMP_QCS21002JB34
J 0
(-2910 1350);
DISPLAY 0.638298 (-2910 1350);
PAINT SKYBLUE (-2910 1350);
DISPLAY INVISIBLE (-2910 1350);
FORCEPROP 1 LAST PATH I45
J 0
(-2900 1700);
DISPLAY 0.978723 (-2900 1700);
PAINT WHITE (-2900 1700);
DISPLAY INVISIBLE (-2900 1700);
FORCEPROP 2 LAST CDS_LIB pure_quanta
J 0
(-2950 1525);
DISPLAY INVISIBLE (-2950 1525);
FORCEADD UNIVERSAL_GND..1
(-3350 1975);
FORCEPROP 3 LASTPIN (-3350 2025) SIG_NAME GND\g
J 0
(-3340 2035);
DISPLAY 0.659574 (-3340 2035);
PAINT MONO (-3340 2035);
DISPLAY INVISIBLE (-3340 2035);
FORCEPROP 1 LAST HDL_POWER GND
J 1
(-3325 1900);
DISPLAY 0.872340 (-3325 1900);
PAINT GREEN (-3325 1900);
DISPLAY INVISIBLE (-3325 1900);
FORCEPROP 1 LAST PATH I46
J 0
(-3275 1975);
DISPLAY 0.872340 (-3275 1975);
PAINT AQUA (-3275 1975);
DISPLAY INVISIBLE (-3275 1975);
FORCEPROP 2 LAST CDS_LIB pure_quanta_power
J 0
(-3350 1975);
DISPLAY INVISIBLE (-3350 1975);
FORCEADD MOSFET_N_GSD..1
(-2975 1100);
FORCEPROP 1 LAST LOCATION Q14
J 0
(-2874 1145);
DISPLAY 0.489362 (-2874 1145);
PAINT SKYBLUE (-2874 1145);
FORCEPROP 2 LAST $SEC 1
J 0
(-2875 1325);
DISPLAY 0.680851 (-2875 1325);
PAINT MONO (-2875 1325);
DISPLAY INVISIBLE (-2875 1325);
FORCEPROP 2 LAST CDS_SEC 1
J 0
(-2875 1325);
DISPLAY 0.680851 (-2875 1325);
DISPLAY INVISIBLE (-2875 1325);
FORCEPROP 2 LASTPIN (-2950 1250) $PN D
R 1
J 0
(-2960 1260);
DISPLAY 0.489362 (-2960 1260);
PAINT MONO (-2960 1260);
FORCEPROP 2 LASTPIN (-3150 1050) $PN G
J 2
(-3160 1060);
DISPLAY 0.489362 (-3160 1060);
PAINT MONO (-3160 1060);
FORCEPROP 2 LASTPIN (-2950 950) $PN S
R 1
J 2
(-2960 940);
DISPLAY 0.489362 (-2960 940);
PAINT MONO (-2960 940);
FORCEPROP 1 LAST PART_NUMBER BAM01380023
J 0
(-2874 1080);
DISPLAY 0.489362 (-2874 1080);
PAINT SKYBLUE (-2874 1080);
FORCEPROP 2 LAST VALUE NX138BK
J 0
(-2875 1225);
DISPLAY 0.489362 (-2875 1225);
PAINT SKYBLUE (-2875 1225);
FORCEPROP 1 LAST MATERIAL IC
J 0
(-2874 1000);
DISPLAY 0.489362 (-2874 1000);
PAINT SKYBLUE (-2874 1000);
FORCEPROP 2 LAST PART_TYPE SMLF
J 0
(-2875 1275);
DISPLAY 1.021277 (-2875 1275);
FORCEPROP 1 LAST PATH I47
J 0
(-2975 1100);
DISPLAY 0.723404 (-2975 1100);
PAINT GREEN (-2975 1100);
DISPLAY INVISIBLE (-2975 1100);
FORCEPROP 2 LAST CDS_LIB pure_quanta
J 0
(-2975 1100);
DISPLAY INVISIBLE (-2975 1100);
FORCEPROP 1 LAST CDS_LMAN_SYM_OUTLINE -100,100,100,-100
J 0
(-2975 1100);
DISPLAY 0.468085 (-2975 1100);
PAINT GREEN (-2975 1100);
DISPLAY INVISIBLE (-2975 1100);
FORCEPROP 1 LAST NEEDS_NO_SIZE TRUE
J 0
(-2975 1100);
DISPLAY 0.468085 (-2975 1100);
PAINT GREEN (-2975 1100);
DISPLAY INVISIBLE (-2975 1100);
FORCEADD Q_RES..1
R 1
(-3325 825);
FORCEPROP 1 LAST LOCATION R1193
J 0
(-3275 1000);
DISPLAY 0.489362 (-3275 1000);
PAINT SKYBLUE (-3275 1000);
FORCEPROP 2 LAST $SEC 1
R 1
J 0
(-3525 775);
DISPLAY 0.680851 (-3525 775);
PAINT MONO (-3525 775);
DISPLAY INVISIBLE (-3525 775);
FORCEPROP 2 LAST CDS_SEC 1
R 1
J 0
(-3525 775);
DISPLAY 1.021277 (-3525 775);
DISPLAY INVISIBLE (-3525 775);
FORCEPROP 1 LASTPIN (-3325 725) $PN 1
R 1
J 0
(-3337 737);
DISPLAY 0.489362 (-3337 737);
FORCEPROP 1 LASTPIN (-3325 925) $PN 2
R 1
J 0
(-3337 887);
DISPLAY 0.489362 (-3337 887);
FORCEPROP 1 LAST PACK_TYPE 0402LF
J 0
(-3275 750);
DISPLAY 0.489362 (-3275 750);
PAINT SKYBLUE (-3275 750);
FORCEPROP 1 LAST VALUE 100K
J 2
(-3175 900);
DISPLAY 0.489362 (-3175 900);
PAINT SKYBLUE (-3175 900);
FORCEPROP 1 LAST TOLERANCE 1%
J 0
(-3275 950);
DISPLAY 0.489362 (-3275 950);
PAINT SKYBLUE (-3275 950);
FORCEPROP 1 LAST MATERIAL CHIP
J 0
(-3275 800);
DISPLAY 0.489362 (-3275 800);
PAINT SKYBLUE (-3275 800);
FORCEPROP 1 LAST WATTAGE 1/16W
J 2
(-3150 850);
DISPLAY 0.489362 (-3150 850);
PAINT SKYBLUE (-3150 850);
FORCEPROP 1 LAST PART_NUMBER TMP_QCS41002FB28
J 0
(-3300 675);
DISPLAY 0.489362 (-3300 675);
PAINT SKYBLUE (-3300 675);
DISPLAY INVISIBLE (-3300 675);
FORCEPROP 1 LAST PATH I48
R 1
J 0
(-3475 775);
DISPLAY 0.978723 (-3475 775);
PAINT WHITE (-3475 775);
DISPLAY INVISIBLE (-3475 775);
FORCEPROP 2 LAST CDS_LIB pure_quanta
R 1
J 0
(-3325 825);
PAINT MONO (-3325 825);
DISPLAY INVISIBLE (-3325 825);
FORCEADD UNIVERSAL_GND..1
(-3325 575);
FORCEPROP 3 LASTPIN (-3325 625) SIG_NAME GND\g
J 0
(-3315 635);
DISPLAY 0.659574 (-3315 635);
PAINT MONO (-3315 635);
DISPLAY INVISIBLE (-3315 635);
FORCEPROP 1 LAST HDL_POWER GND
J 1
(-3300 500);
DISPLAY 0.872340 (-3300 500);
PAINT GREEN (-3300 500);
DISPLAY INVISIBLE (-3300 500);
FORCEPROP 1 LAST PATH I49
J 0
(-3250 575);
DISPLAY 0.872340 (-3250 575);
PAINT AQUA (-3250 575);
DISPLAY INVISIBLE (-3250 575);
FORCEPROP 2 LAST CDS_LIB pure_quanta_power
J 0
(-3325 575);
DISPLAY INVISIBLE (-3325 575);
FORCEADD OFFPAGE..1
(-3875 1050);
FORCEPROP 2 LAST $XR0 80 
J 0
(-4126 1050);
DISPLAY 0.638298 (-4126 1050);
PAINT MONO (-4126 1050);
FORCEPROP 2 LAST PATH I50
J 0
(-3825 1125);
DISPLAY 0.680851 (-3825 1125);
DISPLAY INVISIBLE (-3825 1125);
FORCEPROP 1 LAST COMMENT_BODY TRUE
J 0
(-3750 950);
DISPLAY 0.872340 (-3750 950);
PAINT GREEN (-3750 950);
DISPLAY INVISIBLE (-3750 950);
FORCEPROP 1 LAST OFFPAGE TRUE
J 0
(-3550 925);
DISPLAY 0.872340 (-3550 925);
PAINT GREEN (-3550 925);
DISPLAY INVISIBLE (-3550 925);
FORCEPROP 2 LAST CDS_LIB standard
J 0
(-3875 1050);
DISPLAY INVISIBLE (-3875 1050);
FORCEADD VCC_CORE..1
(-6200 6350);
FORCEPROP 3 LASTPIN (-6200 6300) SIG_NAME P3V3_STBY\g
J 0
(-6190 6310);
DISPLAY 0.659574 (-6190 6310);
PAINT MONO (-6190 6310);
DISPLAY INVISIBLE (-6190 6310);
FORCEPROP 1 LAST HDL_POWER P3V3_STBY
J 1
(-6200 6400);
DISPLAY 0.489362 (-6200 6400);
PAINT GREEN (-6200 6400);
FORCEPROP 1 LAST PATH I51
J 0
(-6150 6375);
DISPLAY 0.872340 (-6150 6375);
PAINT AQUA (-6150 6375);
DISPLAY INVISIBLE (-6150 6375);
FORCEPROP 2 LAST CDS_LIB pure_quanta_power
J 0
(-6200 6350);
DISPLAY INVISIBLE (-6200 6350);
FORCEADD Q_RES..2
(-6200 6050);
FORCEPROP 1 LAST LOCATION R673
J 0
(-6155 6175);
DISPLAY 0.489362 (-6155 6175);
PAINT SKYBLUE (-6155 6175);
FORCEPROP 0 LAST $SEC 1
J 0
(-6150 6225);
DISPLAY 0.680851 (-6150 6225);
PAINT MONO (-6150 6225);
DISPLAY INVISIBLE (-6150 6225);
FORCEPROP 0 LAST CDS_SEC 1
J 0
(-6150 6225);
DISPLAY 1.021277 (-6150 6225);
DISPLAY INVISIBLE (-6150 6225);
FORCEPROP 1 LASTPIN (-6200 6150) $PN 1
J 0
(-6195 6112);
DISPLAY 0.489362 (-6195 6112);
PAINT MONO (-6195 6112);
FORCEPROP 1 LASTPIN (-6200 5950) $PN 2
J 0
(-6195 5960);
DISPLAY 0.489362 (-6195 5960);
PAINT MONO (-6195 5960);
FORCEPROP 1 LAST PACK_TYPE 0402LF
J 0
(-6160 5950);
DISPLAY 0.489362 (-6160 5950);
PAINT SKYBLUE (-6160 5950);
FORCEPROP 1 LAST PART_NUMBER TMP_QCS21002JB34
J 0
(-6150 5900);
DISPLAY 0.489362 (-6150 5900);
PAINT SKYBLUE (-6150 5900);
FORCEPROP 1 LAST VALUE 1K
J 0
(-6155 6150);
DISPLAY 0.489362 (-6155 6150);
PAINT SKYBLUE (-6155 6150);
FORCEPROP 1 LAST TOLERANCE 5%
J 0
(-6155 6100);
DISPLAY 0.489362 (-6155 6100);
PAINT SKYBLUE (-6155 6100);
FORCEPROP 1 LAST MATERIAL CHIP
J 0
(-6160 6000);
DISPLAY 0.489362 (-6160 6000);
PAINT SKYBLUE (-6160 6000);
FORCEPROP 1 LAST WATTAGE 1/16W
J 0
(-6160 6050);
DISPLAY 0.489362 (-6160 6050);
PAINT SKYBLUE (-6160 6050);
FORCEPROP 1 LAST PATH I52
J 0
(-6150 6225);
DISPLAY 0.978723 (-6150 6225);
PAINT WHITE (-6150 6225);
DISPLAY INVISIBLE (-6150 6225);
FORCEPROP 2 LAST CDS_LIB pure_quanta
J 0
(-6200 6050);
DISPLAY INVISIBLE (-6200 6050);
FORCEADD OFFPAGE..5
R 2
(-5575 5725);
FORCEPROP 2 LAST $XR0 117 
J 0
(-5386 5725);
DISPLAY 0.638298 (-5386 5725);
PAINT MONO (-5386 5725);
FORCEPROP 2 LAST PATH I53
J 0
(-5375 5775);
DISPLAY 0.680851 (-5375 5775);
DISPLAY INVISIBLE (-5375 5775);
FORCEPROP 1 LAST COMMENT_BODY TRUE
J 2
(-5675 5650);
DISPLAY 0.872340 (-5675 5650);
PAINT GREEN (-5675 5650);
DISPLAY INVISIBLE (-5675 5650);
FORCEPROP 1 LAST OFFPAGE TRUE
J 2
(-5900 5600);
DISPLAY 0.872340 (-5900 5600);
PAINT GREEN (-5900 5600);
DISPLAY INVISIBLE (-5900 5600);
FORCEPROP 2 LAST CDS_LIB standard
J 2
(-5575 5725);
DISPLAY INVISIBLE (-5575 5725);
FORCEADD OFFPAGE..1
R 2
(-6450 5775);
FORCEPROP 2 LAST $XR0 83 
J 0
(-6174 5775);
DISPLAY 0.638298 (-6174 5775);
PAINT MONO (-6174 5775);
FORCEPROP 2 LAST PATH I54
J 0
(-6150 5825);
DISPLAY 0.680851 (-6150 5825);
DISPLAY INVISIBLE (-6150 5825);
FORCEPROP 1 LAST COMMENT_BODY TRUE
J 2
(-6575 5675);
DISPLAY 0.872340 (-6575 5675);
PAINT GREEN (-6575 5675);
DISPLAY INVISIBLE (-6575 5675);
FORCEPROP 1 LAST OFFPAGE TRUE
J 2
(-6775 5650);
DISPLAY 0.872340 (-6775 5650);
PAINT GREEN (-6775 5650);
DISPLAY INVISIBLE (-6775 5650);
FORCEPROP 2 LAST CDS_LIB standard
J 0
(-6450 5775);
DISPLAY INVISIBLE (-6450 5775);
FORCEADD Q_RES..1
R 2
(-6550 5725);
FORCEPROP 1 LAST LOCATION R672
J 2
(-6400 5725);
DISPLAY 0.489362 (-6400 5725);
PAINT SKYBLUE (-6400 5725);
FORCEPROP 0 LAST $SEC 1
J 2
(-6400 5775);
DISPLAY 0.680851 (-6400 5775);
PAINT MONO (-6400 5775);
DISPLAY INVISIBLE (-6400 5775);
FORCEPROP 0 LAST CDS_SEC 1
J 2
(-6400 5775);
DISPLAY 1.021277 (-6400 5775);
DISPLAY INVISIBLE (-6400 5775);
FORCEPROP 1 LASTPIN (-6450 5725) $PN 1
J 2
(-6462 5737);
DISPLAY 0.489362 (-6462 5737);
PAINT MONO (-6462 5737);
FORCEPROP 1 LASTPIN (-6650 5725) $PN 2
J 2
(-6612 5737);
DISPLAY 0.489362 (-6612 5737);
PAINT MONO (-6612 5737);
FORCEPROP 1 LAST VALUE 33
J 0
(-6700 5725);
DISPLAY 0.489362 (-6700 5725);
PAINT SKYBLUE (-6700 5725);
FORCEPROP 1 LAST PACK_TYPE 0402LF
J 2
(-6675 5700);
DISPLAY 0.489362 (-6675 5700);
PAINT SKYBLUE (-6675 5700);
DISPLAY INVISIBLE (-6675 5700);
FORCEPROP 1 LAST PART_NUMBER CS03302JB29
J 2
(-6375 5650);
DISPLAY 0.510638 (-6375 5650);
PAINT SKYBLUE (-6375 5650);
DISPLAY INVISIBLE (-6375 5650);
FORCEPROP 1 LAST TOLERANCE 5%
J 2
(-6750 5725);
DISPLAY 0.510638 (-6750 5725);
PAINT SKYBLUE (-6750 5725);
DISPLAY INVISIBLE (-6750 5725);
FORCEPROP 1 LAST MATERIAL CHIP
J 2
(-6675 5675);
DISPLAY 0.489362 (-6675 5675);
PAINT SKYBLUE (-6675 5675);
DISPLAY INVISIBLE (-6675 5675);
FORCEPROP 1 LAST WATTAGE 1/16W
J 0
(-6925 5750);
DISPLAY 0.510638 (-6925 5750);
PAINT SKYBLUE (-6925 5750);
DISPLAY INVISIBLE (-6925 5750);
FORCEPROP 1 LAST PATH I55
J 2
(-6500 5875);
DISPLAY 0.978723 (-6500 5875);
PAINT WHITE (-6500 5875);
DISPLAY INVISIBLE (-6500 5875);
FORCEPROP 2 LAST CDS_LIB pure_quanta
J 2
(-6550 5725);
DISPLAY INVISIBLE (-6550 5725);
FORCEADD VCC_CORE..1
(-8650 6200);
FORCEPROP 3 LASTPIN (-8650 6150) SIG_NAME P3V3_STBY\g
J 0
(-8640 6160);
DISPLAY 0.659574 (-8640 6160);
PAINT MONO (-8640 6160);
DISPLAY INVISIBLE (-8640 6160);
FORCEPROP 1 LAST HDL_POWER P3V3_STBY
J 1
(-8650 6250);
DISPLAY 0.489362 (-8650 6250);
PAINT GREEN (-8650 6250);
FORCEPROP 1 LAST PATH I59
J 0
(-8600 6225);
DISPLAY 0.872340 (-8600 6225);
PAINT AQUA (-8600 6225);
DISPLAY INVISIBLE (-8600 6225);
FORCEPROP 2 LAST CDS_LIB pure_quanta_power
J 0
(-8650 6200);
DISPLAY INVISIBLE (-8650 6200);
FORCEADD GND..1
R 1
(-7175 5825);
FORCEPROP 3 LASTPIN (-7225 5825) SIG_NAME GND\g
J 0
(-7215 5835);
DISPLAY 0.659574 (-7215 5835);
PAINT MONO (-7215 5835);
DISPLAY INVISIBLE (-7215 5835);
FORCEPROP 1 LAST HDL_POWER GND
R 1
J 0
(-7325 5825);
DISPLAY 0.851064 (-7325 5825);
PAINT GREEN (-7325 5825);
DISPLAY INVISIBLE (-7325 5825);
FORCEPROP 1 LAST PATH I60
R 1
J 0
(-7175 5900);
DISPLAY 0.872340 (-7175 5900);
PAINT AQUA (-7175 5900);
DISPLAY INVISIBLE (-7175 5900);
FORCEPROP 2 LAST BOM_COST MEM
R 1
J 0
(-7250 5725);
DISPLAY 0.808511 (-7250 5725);
DISPLAY INVISIBLE (-7250 5725);
FORCEPROP 1 LAST SIZE 1B
R 1
J 0
(-7125 5900);
DISPLAY 0.851064 (-7125 5900);
PAINT GREEN (-7125 5900);
DISPLAY INVISIBLE (-7125 5900);
FORCEPROP 2 LAST CDS_LIB pure_quanta_power
R 1
J 0
(-7175 5825);
DISPLAY INVISIBLE (-7175 5825);
FORCEADD MOSFET_DUAL_6P..1
(-7575 5775);
FORCEPROP 1 LAST LOCATION Q6
J 0
(-7722 5984);
DISPLAY 0.489362 (-7722 5984);
PAINT SKYBLUE (-7722 5984);
FORCEPROP 2 LAST $SEC 1
J 0
(-7700 6125);
DISPLAY 0.680851 (-7700 6125);
PAINT MONO (-7700 6125);
DISPLAY INVISIBLE (-7700 6125);
FORCEPROP 2 LAST CDS_SEC 1
J 0
(-7700 6125);
DISPLAY 0.680851 (-7700 6125);
DISPLAY INVISIBLE (-7700 6125);
FORCEPROP 2 LASTPIN (-7875 5725) $PN 6
J 2
(-7885 5735);
DISPLAY 0.489362 (-7885 5735);
PAINT MONO (-7885 5735);
FORCEPROP 2 LASTPIN (-7275 5725) $PN 3
J 0
(-7265 5735);
DISPLAY 0.489362 (-7265 5735);
PAINT MONO (-7265 5735);
FORCEPROP 2 LASTPIN (-7875 5775) $PN 2
J 2
(-7885 5785);
DISPLAY 0.489362 (-7885 5785);
PAINT MONO (-7885 5785);
FORCEPROP 2 LASTPIN (-7275 5775) $PN 5
J 0
(-7265 5785);
DISPLAY 0.489362 (-7265 5785);
PAINT MONO (-7265 5785);
FORCEPROP 2 LASTPIN (-7875 5825) $PN 1
J 2
(-7885 5835);
DISPLAY 0.489362 (-7885 5835);
PAINT MONO (-7885 5835);
FORCEPROP 2 LASTPIN (-7275 5825) $PN 4
J 0
(-7265 5835);
DISPLAY 0.489362 (-7265 5835);
PAINT MONO (-7265 5835);
FORCEPROP 1 LAST PART_NUMBER BAM70020047
J 0
(-7722 5942);
DISPLAY 0.489362 (-7722 5942);
PAINT SKYBLUE (-7722 5942);
FORCEPROP 2 LAST VALUE 2N7002KDW
J 0
(-7700 6025);
DISPLAY 0.489362 (-7700 6025);
PAINT SKYBLUE (-7700 6025);
FORCEPROP 1 LAST MATERIAL IC
J 0
(-7722 5898);
DISPLAY 0.489362 (-7722 5898);
PAINT SKYBLUE (-7722 5898);
FORCEPROP 2 LAST PART_TYPE SMLF
J 0
(-7700 6075);
DISPLAY 0.680851 (-7700 6075);
FORCEPROP 1 LAST PATH I61
J 0
(-7575 5775);
DISPLAY 0.723404 (-7575 5775);
PAINT GREEN (-7575 5775);
DISPLAY INVISIBLE (-7575 5775);
FORCEPROP 2 LAST CDS_LIB pure_quanta
J 0
(-7575 5775);
DISPLAY INVISIBLE (-7575 5775);
FORCEPROP 1 LAST CDS_LMAN_SYM_OUTLINE -150,100,150,-100
J 0
(-7575 5775);
DISPLAY 0.468085 (-7575 5775);
PAINT GREEN (-7575 5775);
DISPLAY INVISIBLE (-7575 5775);
FORCEPROP 1 LAST NEEDS_NO_SIZE TRUE
J 0
(-7575 5774);
DISPLAY 0.468085 (-7575 5774);
PAINT GREEN (-7575 5774);
DISPLAY INVISIBLE (-7575 5774);
FORCEADD GND..1
R 7
(-8050 5825);
FORCEPROP 3 LASTPIN (-8000 5825) SIG_NAME GND\g
J 0
(-7990 5835);
DISPLAY 0.659574 (-7990 5835);
PAINT MONO (-7990 5835);
DISPLAY INVISIBLE (-7990 5835);
FORCEPROP 1 LAST HDL_POWER GND
R 1
J 0
(-7900 5825);
DISPLAY 0.851064 (-7900 5825);
PAINT GREEN (-7900 5825);
DISPLAY INVISIBLE (-7900 5825);
FORCEPROP 1 LAST PATH I62
R 1
J 0
(-8050 5900);
DISPLAY 0.872340 (-8050 5900);
PAINT AQUA (-8050 5900);
DISPLAY INVISIBLE (-8050 5900);
FORCEPROP 2 LAST BOM_COST MEM
R 1
J 0
(-7975 5725);
DISPLAY 0.808511 (-7975 5725);
DISPLAY INVISIBLE (-7975 5725);
FORCEPROP 1 LAST SIZE 1B
R 1
J 0
(-8100 5900);
DISPLAY 0.851064 (-8100 5900);
PAINT GREEN (-8100 5900);
DISPLAY INVISIBLE (-8100 5900);
FORCEPROP 2 LAST CDS_LIB pure_quanta_power
J 2
(-8050 5825);
DISPLAY INVISIBLE (-8050 5825);
FORCEADD Q_RES..2
R 2
(-7950 5550);
FORCEPROP 1 LAST LOCATION R1308
J 2
(-7995 5675);
DISPLAY 0.489362 (-7995 5675);
PAINT SKYBLUE (-7995 5675);
FORCEPROP 2 LAST $SEC 1
J 0
(-8000 5775);
DISPLAY 0.680851 (-8000 5775);
PAINT MONO (-8000 5775);
DISPLAY INVISIBLE (-8000 5775);
FORCEPROP 2 LAST CDS_SEC 1
J 0
(-8000 5775);
DISPLAY 0.680851 (-8000 5775);
DISPLAY INVISIBLE (-8000 5775);
FORCEPROP 1 LASTPIN (-7950 5650) $PN 1
J 2
(-7955 5612);
DISPLAY 0.489362 (-7955 5612);
PAINT MONO (-7955 5612);
FORCEPROP 1 LASTPIN (-7950 5450) $PN 2
J 2
(-7955 5460);
DISPLAY 0.489362 (-7955 5460);
PAINT MONO (-7955 5460);
FORCEPROP 1 LAST PACK_TYPE 0402LF
J 2
(-7990 5450);
DISPLAY 0.489362 (-7990 5450);
PAINT SKYBLUE (-7990 5450);
FORCEPROP 1 LAST PART_NUMBER TMP_QCS24702JB38
J 2
(-8000 5400);
DISPLAY 0.489362 (-8000 5400);
PAINT SKYBLUE (-8000 5400);
FORCEPROP 1 LAST VALUE 4.7K
J 2
(-7995 5650);
DISPLAY 0.489362 (-7995 5650);
PAINT SKYBLUE (-7995 5650);
FORCEPROP 1 LAST TOLERANCE 5%
J 2
(-7995 5600);
DISPLAY 0.489362 (-7995 5600);
PAINT SKYBLUE (-7995 5600);
FORCEPROP 1 LAST MATERIAL CHIP
J 2
(-7990 5500);
DISPLAY 0.489362 (-7990 5500);
PAINT SKYBLUE (-7990 5500);
FORCEPROP 1 LAST WATTAGE 1/16W
J 2
(-7990 5550);
DISPLAY 0.489362 (-7990 5550);
PAINT SKYBLUE (-7990 5550);
FORCEPROP 1 LAST PATH I63
J 2
(-8000 5725);
DISPLAY 0.978723 (-8000 5725);
PAINT WHITE (-8000 5725);
DISPLAY INVISIBLE (-8000 5725);
FORCEPROP 2 LAST CDS_LIB pure_quanta
J 0
(-7950 5550);
DISPLAY INVISIBLE (-7950 5550);
FORCEADD GND..1
(-7950 5325);
FORCEPROP 3 LASTPIN (-7950 5375) SIG_NAME GND\g
J 0
(-7940 5385);
DISPLAY 0.659574 (-7940 5385);
PAINT MONO (-7940 5385);
DISPLAY INVISIBLE (-7940 5385);
FORCEPROP 1 LAST HDL_POWER GND
J 0
(-7950 5475);
DISPLAY 0.851064 (-7950 5475);
PAINT GREEN (-7950 5475);
DISPLAY INVISIBLE (-7950 5475);
FORCEPROP 1 LAST PATH I64
J 0
(-7875 5325);
DISPLAY 0.872340 (-7875 5325);
PAINT AQUA (-7875 5325);
DISPLAY INVISIBLE (-7875 5325);
FORCEPROP 1 LAST SIZE 1B
J 0
(-7875 5275);
DISPLAY 0.851064 (-7875 5275);
PAINT GREEN (-7875 5275);
DISPLAY INVISIBLE (-7875 5275);
FORCEPROP 2 LAST BOM_COST MEM
J 0
(-8050 5400);
DISPLAY 0.808511 (-8050 5400);
DISPLAY INVISIBLE (-8050 5400);
FORCEPROP 2 LAST CDS_LIB pure_quanta_power
J 0
(-7950 5325);
DISPLAY INVISIBLE (-7950 5325);
FORCEADD SN74LVC1G07DBVR..1
(-7175 4300);
FORCEPROP 1 LAST LOCATION U92
J 0
(-7300 4555);
DISPLAY 0.489362 (-7300 4555);
PAINT SKYBLUE (-7300 4555);
FORCEPROP 0 LAST $SEC 1
J 0
(-7300 4700);
DISPLAY 0.680851 (-7300 4700);
PAINT MONO (-7300 4700);
DISPLAY INVISIBLE (-7300 4700);
FORCEPROP 0 LAST CDS_SEC 1
J 0
(-7300 4700);
DISPLAY 0.680851 (-7300 4700);
DISPLAY INVISIBLE (-7300 4700);
FORCEPROP 0 LASTPIN (-7350 4300) $PN 2
J 2
(-7360 4310);
DISPLAY 0.489362 (-7360 4310);
PAINT MONO (-7360 4310);
FORCEPROP 0 LASTPIN (-7350 4200) $PN 3
J 2
(-7360 4210);
DISPLAY 0.489362 (-7360 4210);
PAINT MONO (-7360 4210);
FORCEPROP 0 LASTPIN (-7000 4200) $PN 1
J 0
(-6990 4210);
DISPLAY 0.489362 (-6990 4210);
PAINT MONO (-6990 4210);
FORCEPROP 0 LASTPIN (-7350 4400) $PN 5
J 2
(-7360 4410);
DISPLAY 0.489362 (-7360 4410);
PAINT MONO (-7360 4410);
FORCEPROP 0 LASTPIN (-7000 4300) $PN 4
J 0
(-6990 4310);
DISPLAY 0.489362 (-6990 4310);
PAINT MONO (-6990 4310);
FORCEPROP 2 LAST PACK_TYPE SMLF
J 0
(-7300 4600);
DISPLAY 0.489362 (-7300 4600);
PAINT SKYBLUE (-7300 4600);
FORCEPROP 1 LAST PART_NUMBER AL1G0007024
J 0
(-7300 4510);
DISPLAY 0.489362 (-7300 4510);
PAINT SKYBLUE (-7300 4510);
FORCEPROP 2 LAST VALUE SN74LVC1G07DBVR
J 0
(-7300 4650);
DISPLAY 0.489362 (-7300 4650);
PAINT SKYBLUE (-7300 4650);
FORCEPROP 1 LAST MATERIAL IC
J 0
(-7300 4460);
DISPLAY 0.489362 (-7300 4460);
PAINT SKYBLUE (-7300 4460);
FORCEPROP 1 LAST PATH I65
J 0
(-7075 4455);
DISPLAY 0.723404 (-7075 4455);
PAINT GREEN (-7075 4455);
DISPLAY INVISIBLE (-7075 4455);
FORCEPROP 1 LAST NEEDS_NO_SIZE TRUE
J 0
(-7175 4300);
DISPLAY 0.468085 (-7175 4300);
PAINT GREEN (-7175 4300);
DISPLAY INVISIBLE (-7175 4300);
FORCEPROP 2 LAST CDS_LIB pure_quanta
J 0
(-7175 4300);
DISPLAY INVISIBLE (-7175 4300);
FORCEADD UNIVERSAL_GND..1
(-7425 4025);
FORCEPROP 3 LASTPIN (-7425 4075) SIG_NAME GND\g
J 0
(-7415 4085);
DISPLAY 0.659574 (-7415 4085);
PAINT MONO (-7415 4085);
DISPLAY INVISIBLE (-7415 4085);
FORCEPROP 1 LAST HDL_POWER GND
J 1
(-7400 3950);
DISPLAY 0.872340 (-7400 3950);
PAINT GREEN (-7400 3950);
DISPLAY INVISIBLE (-7400 3950);
FORCEPROP 1 LAST PATH I66
J 0
(-7350 4025);
DISPLAY 0.872340 (-7350 4025);
PAINT AQUA (-7350 4025);
DISPLAY INVISIBLE (-7350 4025);
FORCEPROP 2 LAST BOM_COST OCP3.0 
J 0
(-7625 4100);
DISPLAY 0.680851 (-7625 4100);
DISPLAY INVISIBLE (-7625 4100);
FORCEPROP 2 LAST CDS_LIB pure_quanta_power
J 0
(-7425 4025);
DISPLAY INVISIBLE (-7425 4025);
FORCEADD Q_RES..2
(-8650 5975);
FORCEPROP 1 LAST LOCATION R755
J 0
(-8605 6100);
DISPLAY 0.489362 (-8605 6100);
PAINT SKYBLUE (-8605 6100);
FORCEPROP 2 LAST $SEC 1
J 0
(-8600 6200);
DISPLAY 0.680851 (-8600 6200);
PAINT MONO (-8600 6200);
DISPLAY INVISIBLE (-8600 6200);
FORCEPROP 2 LAST CDS_SEC 1
J 0
(-8600 6200);
DISPLAY 0.680851 (-8600 6200);
DISPLAY INVISIBLE (-8600 6200);
FORCEPROP 1 LASTPIN (-8650 6075) $PN 1
J 0
(-8645 6037);
DISPLAY 0.489362 (-8645 6037);
PAINT MONO (-8645 6037);
FORCEPROP 1 LASTPIN (-8650 5875) $PN 2
J 0
(-8645 5885);
DISPLAY 0.489362 (-8645 5885);
PAINT MONO (-8645 5885);
FORCEPROP 1 LAST PACK_TYPE 0402LF
J 0
(-8610 5875);
DISPLAY 0.489362 (-8610 5875);
PAINT SKYBLUE (-8610 5875);
FORCEPROP 1 LAST PART_NUMBER TMP_QCS24702JB38
J 0
(-8600 5825);
DISPLAY 0.489362 (-8600 5825);
PAINT SKYBLUE (-8600 5825);
FORCEPROP 1 LAST VALUE 4.7K
J 0
(-8605 6075);
DISPLAY 0.489362 (-8605 6075);
PAINT SKYBLUE (-8605 6075);
FORCEPROP 1 LAST TOLERANCE 5%
J 0
(-8605 6025);
DISPLAY 0.489362 (-8605 6025);
PAINT SKYBLUE (-8605 6025);
FORCEPROP 1 LAST MATERIAL CHIP
J 0
(-8610 5925);
DISPLAY 0.489362 (-8610 5925);
PAINT SKYBLUE (-8610 5925);
FORCEPROP 1 LAST WATTAGE 1/16W
J 0
(-8610 5975);
DISPLAY 0.489362 (-8610 5975);
PAINT SKYBLUE (-8610 5975);
FORCEPROP 1 LAST PATH I67
J 0
(-8600 6150);
DISPLAY 0.978723 (-8600 6150);
PAINT WHITE (-8600 6150);
DISPLAY INVISIBLE (-8600 6150);
FORCEPROP 2 LAST CDS_LIB pure_quanta
J 0
(-8650 5975);
DISPLAY INVISIBLE (-8650 5975);
FORCEADD UNIVERSAL_POWER..1
(-7775 4925);
FORCEPROP 3 LASTPIN (-7775 4875) SIG_NAME P1V8_STBY\g
J 0
(-7765 4885);
DISPLAY 0.659574 (-7765 4885);
PAINT MONO (-7765 4885);
DISPLAY INVISIBLE (-7765 4885);
FORCEPROP 1 LAST HDL_POWER P1V8_STBY
J 1
(-7775 4975);
DISPLAY 0.489362 (-7775 4975);
PAINT GREEN (-7775 4975);
FORCEPROP 1 LAST PATH I68
J 0
(-7725 4950);
DISPLAY 0.872340 (-7725 4950);
PAINT AQUA (-7725 4950);
DISPLAY INVISIBLE (-7725 4950);
FORCEPROP 2 LAST BOM_COST OCP3.0 
J 0
(-7775 5025);
DISPLAY 0.680851 (-7775 5025);
DISPLAY INVISIBLE (-7775 5025);
FORCEPROP 2 LAST CDS_LIB pure_quanta_power
J 0
(-7775 4925);
DISPLAY INVISIBLE (-7775 4925);
FORCEADD OFFPAGE..5
(-8750 5725);
FORCEPROP 2 LAST $XR0 83 
J 0
(-9004 5725);
DISPLAY 0.638298 (-9004 5725);
PAINT MONO (-9004 5725);
FORCEPROP 2 LAST PATH I69
J 0
(-9000 5775);
DISPLAY 0.680851 (-9000 5775);
DISPLAY INVISIBLE (-9000 5775);
FORCEPROP 1 LAST COMMENT_BODY TRUE
J 0
(-8650 5650);
DISPLAY 0.872340 (-8650 5650);
PAINT GREEN (-8650 5650);
DISPLAY INVISIBLE (-8650 5650);
FORCEPROP 1 LAST OFFPAGE TRUE
J 0
(-8425 5600);
DISPLAY 0.872340 (-8425 5600);
PAINT GREEN (-8425 5600);
DISPLAY INVISIBLE (-8425 5600);
FORCEPROP 2 LAST CDS_LIB standard
J 0
(-8750 5725);
DISPLAY INVISIBLE (-8750 5725);
FORCEADD OFFPAGE..1
(-8750 5775);
FORCEPROP 2 LAST $XR0 79 
J 0
(-8971 5775);
DISPLAY 0.638298 (-8971 5775);
PAINT MONO (-8971 5775);
FORCEPROP 2 LAST PATH I70
J 0
(-8950 5825);
DISPLAY 0.680851 (-8950 5825);
DISPLAY INVISIBLE (-8950 5825);
FORCEPROP 1 LAST COMMENT_BODY TRUE
J 0
(-8625 5675);
DISPLAY 0.872340 (-8625 5675);
PAINT GREEN (-8625 5675);
DISPLAY INVISIBLE (-8625 5675);
FORCEPROP 1 LAST OFFPAGE TRUE
J 0
(-8425 5650);
DISPLAY 0.872340 (-8425 5650);
PAINT GREEN (-8425 5650);
DISPLAY INVISIBLE (-8425 5650);
FORCEPROP 2 LAST CDS_LIB standard
J 0
(-8750 5775);
DISPLAY INVISIBLE (-8750 5775);
FORCEADD UNIVERSAL_GND..1
(-7775 4425);
FORCEPROP 3 LASTPIN (-7775 4475) SIG_NAME GND\g
J 0
(-7765 4485);
DISPLAY 0.659574 (-7765 4485);
PAINT MONO (-7765 4485);
DISPLAY INVISIBLE (-7765 4485);
FORCEPROP 1 LAST HDL_POWER GND
J 1
(-7750 4350);
DISPLAY 0.872340 (-7750 4350);
PAINT GREEN (-7750 4350);
DISPLAY INVISIBLE (-7750 4350);
FORCEPROP 1 LAST PATH I71
J 0
(-7700 4425);
DISPLAY 0.872340 (-7700 4425);
PAINT AQUA (-7700 4425);
DISPLAY INVISIBLE (-7700 4425);
FORCEPROP 2 LAST BOM_COST OCP3.0 
J 0
(-7975 4500);
DISPLAY 0.680851 (-7975 4500);
DISPLAY INVISIBLE (-7975 4500);
FORCEPROP 2 LAST CDS_LIB pure_quanta_power
J 0
(-7775 4425);
DISPLAY INVISIBLE (-7775 4425);
FORCEADD Q_CAP..1
(-7775 4625);
FORCEPROP 1 LAST LOCATION C552
J 0
(-7725 4725);
DISPLAY 0.489362 (-7725 4725);
PAINT SKYBLUE (-7725 4725);
FORCEPROP 0 LAST $SEC 1
J 0
(-7725 4775);
DISPLAY 0.680851 (-7725 4775);
PAINT MONO (-7725 4775);
DISPLAY INVISIBLE (-7725 4775);
FORCEPROP 0 LAST CDS_SEC 1
J 0
(-7725 4775);
DISPLAY 0.680851 (-7725 4775);
DISPLAY INVISIBLE (-7725 4775);
FORCEPROP 1 LASTPIN (-7775 4725) $PN 1
J 0
(-7765 4705);
DISPLAY 0.489362 (-7765 4705);
PAINT MONO (-7765 4705);
FORCEPROP 1 LASTPIN (-7775 4525) $PN 2
J 0
(-7765 4505);
DISPLAY 0.489362 (-7765 4505);
PAINT MONO (-7765 4505);
FORCEPROP 1 LAST PACK_TYPE 0402
J 0
(-7700 4450);
DISPLAY 0.489362 (-7700 4450);
PAINT SKYBLUE (-7700 4450);
FORCEPROP 1 LAST VOLTAGE 25V
J 0
(-7700 4650);
DISPLAY 0.489362 (-7700 4650);
PAINT SKYBLUE (-7700 4650);
FORCEPROP 1 LAST PART_NUMBER CH4104K1B00
J 0
(-7700 4500);
DISPLAY 0.489362 (-7700 4500);
PAINT SKYBLUE (-7700 4500);
FORCEPROP 1 LAST VALUE 0.1UF
J 0
(-7700 4700);
DISPLAY 0.489362 (-7700 4700);
PAINT SKYBLUE (-7700 4700);
FORCEPROP 1 LAST TOLERANCE 10%
J 0
(-7700 4600);
DISPLAY 0.489362 (-7700 4600);
PAINT SKYBLUE (-7700 4600);
FORCEPROP 1 LAST MATERIAL X7R
J 0
(-7700 4550);
DISPLAY 0.489362 (-7700 4550);
PAINT SKYBLUE (-7700 4550);
FORCEPROP 1 LAST PATH I72
J 0
(-7725 4775);
DISPLAY 0.978723 (-7725 4775);
PAINT WHITE (-7725 4775);
DISPLAY INVISIBLE (-7725 4775);
FORCEPROP 2 LAST BOM_COST OCP3.0 
J 0
(-7750 4750);
DISPLAY 0.680851 (-7750 4750);
DISPLAY INVISIBLE (-7750 4750);
FORCEPROP 2 LAST CDS_LIB pure_quanta
J 0
(-7775 4625);
DISPLAY INVISIBLE (-7775 4625);
FORCEADD Q_RES..2
R 2
(-7900 4625);
FORCEPROP 1 LAST LOCATION R996
J 2
(-7945 4750);
DISPLAY 0.489362 (-7945 4750);
PAINT SKYBLUE (-7945 4750);
FORCEPROP 0 LAST $SEC 1
J 0
(-7925 4800);
DISPLAY 0.680851 (-7925 4800);
PAINT MONO (-7925 4800);
DISPLAY INVISIBLE (-7925 4800);
FORCEPROP 0 LAST CDS_SEC 1
J 0
(-7925 4800);
DISPLAY 0.680851 (-7925 4800);
DISPLAY INVISIBLE (-7925 4800);
FORCEPROP 1 LASTPIN (-7900 4725) $PN 1
J 2
(-7905 4687);
DISPLAY 0.489362 (-7905 4687);
PAINT MONO (-7905 4687);
FORCEPROP 1 LASTPIN (-7900 4525) $PN 2
J 2
(-7905 4535);
DISPLAY 0.489362 (-7905 4535);
PAINT MONO (-7905 4535);
FORCEPROP 1 LAST PACK_TYPE 0402LF
J 2
(-7940 4450);
DISPLAY 0.489362 (-7940 4450);
PAINT SKYBLUE (-7940 4450);
FORCEPROP 1 LAST PART_NUMBER TMP_QCS24702JB38
J 2
(-7940 4500);
DISPLAY 0.489362 (-7940 4500);
PAINT SKYBLUE (-7940 4500);
FORCEPROP 1 LAST VALUE 4.7K
J 2
(-7945 4700);
DISPLAY 0.489362 (-7945 4700);
PAINT SKYBLUE (-7945 4700);
FORCEPROP 1 LAST TOLERANCE 5%
J 2
(-7945 4650);
DISPLAY 0.489362 (-7945 4650);
PAINT SKYBLUE (-7945 4650);
FORCEPROP 1 LAST MATERIAL CHIP
J 2
(-7940 4550);
DISPLAY 0.489362 (-7940 4550);
PAINT SKYBLUE (-7940 4550);
FORCEPROP 1 LAST WATTAGE 1/16W
J 2
(-7940 4600);
DISPLAY 0.489362 (-7940 4600);
PAINT SKYBLUE (-7940 4600);
FORCEPROP 1 LAST PATH I73
J 2
(-7950 4800);
DISPLAY 0.978723 (-7950 4800);
PAINT WHITE (-7950 4800);
DISPLAY INVISIBLE (-7950 4800);
FORCEPROP 2 LAST BOM_COST OCP3.0 
J 2
(-7950 4800);
DISPLAY 0.680851 (-7950 4800);
DISPLAY INVISIBLE (-7950 4800);
FORCEPROP 2 LAST CDS_LIB pure_quanta
J 2
(-7900 4625);
DISPLAY INVISIBLE (-7900 4625);
FORCEADD OFFPAGE..1
(-8675 4300);
FORCEPROP 2 LAST $XR0 80 
J 0
(-8896 4300);
DISPLAY 0.638298 (-8896 4300);
PAINT MONO (-8896 4300);
FORCEPROP 2 LAST PATH I74
J 0
(-8925 4350);
DISPLAY 0.680851 (-8925 4350);
DISPLAY INVISIBLE (-8925 4350);
FORCEPROP 1 LAST COMMENT_BODY TRUE
J 0
(-8550 4200);
DISPLAY 0.872340 (-8550 4200);
PAINT GREEN (-8550 4200);
DISPLAY INVISIBLE (-8550 4200);
FORCEPROP 1 LAST OFFPAGE TRUE
J 0
(-8350 4175);
DISPLAY 0.872340 (-8350 4175);
PAINT GREEN (-8350 4175);
DISPLAY INVISIBLE (-8350 4175);
FORCEPROP 2 LAST CDS_LIB standard
J 0
(-8675 4300);
DISPLAY INVISIBLE (-8675 4300);
FORCEADD SN74LVC1G07DBVR..1
(-7225 2975);
FORCEPROP 1 LAST LOCATION U110
J 0
(-7350 3230);
DISPLAY 0.489362 (-7350 3230);
PAINT SKYBLUE (-7350 3230);
FORCEPROP 0 LAST $SEC 1
J 0
(-7350 3350);
DISPLAY 0.680851 (-7350 3350);
PAINT MONO (-7350 3350);
DISPLAY INVISIBLE (-7350 3350);
FORCEPROP 0 LAST CDS_SEC 1
J 0
(-7350 3350);
DISPLAY 0.680851 (-7350 3350);
DISPLAY INVISIBLE (-7350 3350);
FORCEPROP 0 LASTPIN (-7400 2975) $PN 2
J 2
(-7410 2985);
DISPLAY 0.489362 (-7410 2985);
PAINT MONO (-7410 2985);
FORCEPROP 0 LASTPIN (-7400 2875) $PN 3
J 2
(-7410 2885);
DISPLAY 0.489362 (-7410 2885);
PAINT MONO (-7410 2885);
FORCEPROP 0 LASTPIN (-7050 2875) $PN 1
J 0
(-7040 2885);
DISPLAY 0.489362 (-7040 2885);
PAINT MONO (-7040 2885);
FORCEPROP 0 LASTPIN (-7400 3075) $PN 5
J 2
(-7410 3085);
DISPLAY 0.489362 (-7410 3085);
PAINT MONO (-7410 3085);
FORCEPROP 0 LASTPIN (-7050 2975) $PN 4
J 0
(-7040 2985);
DISPLAY 0.489362 (-7040 2985);
PAINT MONO (-7040 2985);
FORCEPROP 2 LAST PACK_TYPE SMLF
J 0
(-7350 3275);
DISPLAY 0.489362 (-7350 3275);
PAINT SKYBLUE (-7350 3275);
FORCEPROP 1 LAST PART_NUMBER AL1G0007024
J 0
(-7350 3185);
DISPLAY 0.489362 (-7350 3185);
PAINT SKYBLUE (-7350 3185);
FORCEPROP 2 LAST VALUE SN74LVC1G07DBVR
J 0
(-7350 3325);
DISPLAY 0.489362 (-7350 3325);
PAINT SKYBLUE (-7350 3325);
FORCEPROP 1 LAST MATERIAL IC
J 0
(-7350 3135);
DISPLAY 0.489362 (-7350 3135);
PAINT SKYBLUE (-7350 3135);
FORCEPROP 1 LAST PATH I83
J 0
(-7125 3130);
DISPLAY 0.723404 (-7125 3130);
PAINT GREEN (-7125 3130);
DISPLAY INVISIBLE (-7125 3130);
FORCEPROP 2 LAST CDS_LIB pure_quanta
J 0
(-7225 2975);
DISPLAY INVISIBLE (-7225 2975);
FORCEPROP 1 LAST NEEDS_NO_SIZE TRUE
J 0
(-7225 2975);
DISPLAY 0.468085 (-7225 2975);
PAINT GREEN (-7225 2975);
DISPLAY INVISIBLE (-7225 2975);
FORCEADD UNIVERSAL_POWER..1
(-7825 3600);
FORCEPROP 3 LASTPIN (-7825 3550) SIG_NAME P1V8_STBY\g
J 0
(-7815 3560);
DISPLAY 0.659574 (-7815 3560);
PAINT MONO (-7815 3560);
DISPLAY INVISIBLE (-7815 3560);
FORCEPROP 1 LAST HDL_POWER P1V8_STBY
J 1
(-7825 3650);
DISPLAY 0.489362 (-7825 3650);
PAINT GREEN (-7825 3650);
FORCEPROP 1 LAST PATH I84
J 0
(-7775 3625);
DISPLAY 0.872340 (-7775 3625);
PAINT AQUA (-7775 3625);
DISPLAY INVISIBLE (-7775 3625);
FORCEPROP 2 LAST BOM_COST OCP3.0 
J 0
(-7825 3700);
DISPLAY 0.680851 (-7825 3700);
DISPLAY INVISIBLE (-7825 3700);
FORCEPROP 2 LAST CDS_LIB pure_quanta_power
J 0
(-7825 3600);
DISPLAY INVISIBLE (-7825 3600);
FORCEADD Q_CAP..1
(-7825 3300);
FORCEPROP 1 LAST LOCATION C68
J 0
(-7775 3400);
DISPLAY 0.489362 (-7775 3400);
PAINT SKYBLUE (-7775 3400);
FORCEPROP 0 LAST $SEC 1
J 0
(-7775 3425);
DISPLAY 0.680851 (-7775 3425);
PAINT MONO (-7775 3425);
DISPLAY INVISIBLE (-7775 3425);
FORCEPROP 0 LAST CDS_SEC 1
J 0
(-7775 3425);
DISPLAY 0.680851 (-7775 3425);
DISPLAY INVISIBLE (-7775 3425);
FORCEPROP 1 LASTPIN (-7825 3400) $PN 1
J 0
(-7815 3380);
DISPLAY 0.489362 (-7815 3380);
PAINT MONO (-7815 3380);
FORCEPROP 1 LASTPIN (-7825 3200) $PN 2
J 0
(-7815 3180);
DISPLAY 0.489362 (-7815 3180);
PAINT MONO (-7815 3180);
FORCEPROP 1 LAST PACK_TYPE 0402
J 0
(-7750 3125);
DISPLAY 0.489362 (-7750 3125);
PAINT SKYBLUE (-7750 3125);
FORCEPROP 1 LAST VOLTAGE 25V
J 0
(-7750 3325);
DISPLAY 0.489362 (-7750 3325);
PAINT SKYBLUE (-7750 3325);
FORCEPROP 1 LAST PART_NUMBER CH4104K1B00
J 0
(-7750 3175);
DISPLAY 0.489362 (-7750 3175);
PAINT SKYBLUE (-7750 3175);
FORCEPROP 1 LAST VALUE 0.1UF
J 0
(-7750 3375);
DISPLAY 0.489362 (-7750 3375);
PAINT SKYBLUE (-7750 3375);
FORCEPROP 1 LAST TOLERANCE 10%
J 0
(-7750 3275);
DISPLAY 0.489362 (-7750 3275);
PAINT SKYBLUE (-7750 3275);
FORCEPROP 1 LAST MATERIAL X7R
J 0
(-7750 3225);
DISPLAY 0.489362 (-7750 3225);
PAINT SKYBLUE (-7750 3225);
FORCEPROP 1 LAST PATH I85
J 0
(-7775 3450);
DISPLAY 0.978723 (-7775 3450);
PAINT WHITE (-7775 3450);
DISPLAY INVISIBLE (-7775 3450);
FORCEPROP 2 LAST CDS_LIB pure_quanta
J 0
(-7825 3300);
DISPLAY INVISIBLE (-7825 3300);
FORCEPROP 2 LAST BOM_COST OCP3.0 
J 0
(-7800 3425);
DISPLAY 0.680851 (-7800 3425);
DISPLAY INVISIBLE (-7800 3425);
FORCEADD UNIVERSAL_GND..1
(-7825 3100);
FORCEPROP 3 LASTPIN (-7825 3150) SIG_NAME GND\g
J 0
(-7815 3160);
DISPLAY 0.659574 (-7815 3160);
PAINT MONO (-7815 3160);
DISPLAY INVISIBLE (-7815 3160);
FORCEPROP 1 LAST HDL_POWER GND
J 1
(-7800 3025);
DISPLAY 0.872340 (-7800 3025);
PAINT GREEN (-7800 3025);
DISPLAY INVISIBLE (-7800 3025);
FORCEPROP 1 LAST PATH I86
J 0
(-7750 3100);
DISPLAY 0.872340 (-7750 3100);
PAINT AQUA (-7750 3100);
DISPLAY INVISIBLE (-7750 3100);
FORCEPROP 2 LAST BOM_COST OCP3.0 
J 0
(-8025 3175);
DISPLAY 0.680851 (-8025 3175);
DISPLAY INVISIBLE (-8025 3175);
FORCEPROP 2 LAST CDS_LIB pure_quanta_power
J 0
(-7825 3100);
DISPLAY INVISIBLE (-7825 3100);
FORCEADD Q_RES..2
R 2
(-7950 3300);
FORCEPROP 1 LAST LOCATION R419
J 2
(-7995 3425);
DISPLAY 0.489362 (-7995 3425);
PAINT SKYBLUE (-7995 3425);
FORCEPROP 0 LAST $SEC 1
J 0
(-7975 3450);
DISPLAY 0.680851 (-7975 3450);
PAINT MONO (-7975 3450);
DISPLAY INVISIBLE (-7975 3450);
FORCEPROP 0 LAST CDS_SEC 1
J 0
(-7975 3450);
DISPLAY 0.680851 (-7975 3450);
DISPLAY INVISIBLE (-7975 3450);
FORCEPROP 1 LASTPIN (-7950 3400) $PN 1
J 2
(-7955 3362);
DISPLAY 0.489362 (-7955 3362);
PAINT MONO (-7955 3362);
FORCEPROP 1 LASTPIN (-7950 3200) $PN 2
J 2
(-7955 3210);
DISPLAY 0.489362 (-7955 3210);
PAINT MONO (-7955 3210);
FORCEPROP 1 LAST PACK_TYPE 0402LF
J 2
(-7990 3125);
DISPLAY 0.489362 (-7990 3125);
PAINT SKYBLUE (-7990 3125);
FORCEPROP 1 LAST PART_NUMBER TMP_QCS24702JB38
J 2
(-7990 3175);
DISPLAY 0.489362 (-7990 3175);
PAINT SKYBLUE (-7990 3175);
FORCEPROP 1 LAST VALUE 4.7K
J 2
(-7995 3375);
DISPLAY 0.489362 (-7995 3375);
PAINT SKYBLUE (-7995 3375);
FORCEPROP 1 LAST TOLERANCE 5%
J 2
(-7995 3325);
DISPLAY 0.489362 (-7995 3325);
PAINT SKYBLUE (-7995 3325);
FORCEPROP 1 LAST MATERIAL CHIP
J 2
(-7990 3225);
DISPLAY 0.489362 (-7990 3225);
PAINT SKYBLUE (-7990 3225);
FORCEPROP 1 LAST WATTAGE 1/16W
J 2
(-7990 3275);
DISPLAY 0.489362 (-7990 3275);
PAINT SKYBLUE (-7990 3275);
FORCEPROP 1 LAST PATH I87
J 2
(-8000 3475);
DISPLAY 0.978723 (-8000 3475);
PAINT WHITE (-8000 3475);
DISPLAY INVISIBLE (-8000 3475);
FORCEPROP 2 LAST CDS_LIB pure_quanta
J 0
(-7950 3300);
DISPLAY INVISIBLE (-7950 3300);
FORCEPROP 2 LAST BOM_COST OCP3.0 
J 2
(-8000 3475);
DISPLAY 0.680851 (-8000 3475);
DISPLAY INVISIBLE (-8000 3475);
FORCEADD UNIVERSAL_GND..1
(-7475 2700);
FORCEPROP 3 LASTPIN (-7475 2750) SIG_NAME GND\g
J 0
(-7465 2760);
DISPLAY 0.659574 (-7465 2760);
PAINT MONO (-7465 2760);
DISPLAY INVISIBLE (-7465 2760);
FORCEPROP 1 LAST HDL_POWER GND
J 1
(-7450 2625);
DISPLAY 0.872340 (-7450 2625);
PAINT GREEN (-7450 2625);
DISPLAY INVISIBLE (-7450 2625);
FORCEPROP 1 LAST PATH I88
J 0
(-7400 2700);
DISPLAY 0.872340 (-7400 2700);
PAINT AQUA (-7400 2700);
DISPLAY INVISIBLE (-7400 2700);
FORCEPROP 2 LAST BOM_COST OCP3.0 
J 0
(-7675 2775);
DISPLAY 0.680851 (-7675 2775);
DISPLAY INVISIBLE (-7675 2775);
FORCEPROP 2 LAST CDS_LIB pure_quanta_power
J 0
(-7475 2700);
DISPLAY INVISIBLE (-7475 2700);
FORCEADD OFFPAGE..1
(-8725 2975);
FORCEPROP 2 LAST $XR0 80 
J 0
(-8976 2975);
DISPLAY 0.638298 (-8976 2975);
PAINT MONO (-8976 2975);
FORCEPROP 2 LAST PATH I89
J 0
(-8675 3050);
DISPLAY 0.680851 (-8675 3050);
DISPLAY INVISIBLE (-8675 3050);
FORCEPROP 1 LAST COMMENT_BODY TRUE
J 0
(-8600 2875);
DISPLAY 0.872340 (-8600 2875);
PAINT GREEN (-8600 2875);
DISPLAY INVISIBLE (-8600 2875);
FORCEPROP 1 LAST OFFPAGE TRUE
J 0
(-8400 2850);
DISPLAY 0.872340 (-8400 2850);
PAINT GREEN (-8400 2850);
DISPLAY INVISIBLE (-8400 2850);
FORCEPROP 2 LAST CDS_LIB standard
J 0
(-8725 2975);
DISPLAY INVISIBLE (-8725 2975);
FORCEADD OFFPAGE..5
R 2
(-5225 2975);
FORCEPROP 2 LAST $XR0 110 
J 0
(-5036 2975);
DISPLAY 0.638298 (-5036 2975);
PAINT MONO (-5036 2975);
FORCEPROP 2 LAST PATH I90
J 0
(-5050 3050);
DISPLAY 0.680851 (-5050 3050);
DISPLAY INVISIBLE (-5050 3050);
FORCEPROP 1 LAST COMMENT_BODY TRUE
J 2
(-5325 2900);
DISPLAY 0.872340 (-5325 2900);
PAINT GREEN (-5325 2900);
DISPLAY INVISIBLE (-5325 2900);
FORCEPROP 1 LAST OFFPAGE TRUE
J 2
(-5550 2850);
DISPLAY 0.872340 (-5550 2850);
PAINT GREEN (-5550 2850);
DISPLAY INVISIBLE (-5550 2850);
FORCEPROP 2 LAST CDS_LIB standard
J 0
(-5225 2975);
DISPLAY INVISIBLE (-5225 2975);
FORCEADD OFFPAGE..5
R 2
(-5225 2925);
FORCEPROP 2 LAST $XR0 110 
J 0
(-5036 2925);
DISPLAY 0.638298 (-5036 2925);
PAINT MONO (-5036 2925);
FORCEPROP 2 LAST PATH I91
J 0
(-5050 3000);
DISPLAY 0.680851 (-5050 3000);
DISPLAY INVISIBLE (-5050 3000);
FORCEPROP 1 LAST COMMENT_BODY TRUE
J 2
(-5325 2850);
DISPLAY 0.872340 (-5325 2850);
PAINT GREEN (-5325 2850);
DISPLAY INVISIBLE (-5325 2850);
FORCEPROP 1 LAST OFFPAGE TRUE
J 2
(-5550 2800);
DISPLAY 0.872340 (-5550 2800);
PAINT GREEN (-5550 2800);
DISPLAY INVISIBLE (-5550 2800);
FORCEPROP 2 LAST CDS_LIB standard
J 0
(-5225 2925);
DISPLAY INVISIBLE (-5225 2925);
FORCEADD OFFPAGE..5
R 2
(-5225 2875);
FORCEPROP 2 LAST $XR0 111 
J 0
(-5036 2875);
DISPLAY 0.638298 (-5036 2875);
PAINT MONO (-5036 2875);
FORCEPROP 2 LAST PATH I92
J 0
(-5050 2950);
DISPLAY 0.680851 (-5050 2950);
DISPLAY INVISIBLE (-5050 2950);
FORCEPROP 1 LAST COMMENT_BODY TRUE
J 2
(-5325 2800);
DISPLAY 0.872340 (-5325 2800);
PAINT GREEN (-5325 2800);
DISPLAY INVISIBLE (-5325 2800);
FORCEPROP 1 LAST OFFPAGE TRUE
J 2
(-5550 2750);
DISPLAY 0.872340 (-5550 2750);
PAINT GREEN (-5550 2750);
DISPLAY INVISIBLE (-5550 2750);
FORCEPROP 2 LAST CDS_LIB standard
J 0
(-5225 2875);
DISPLAY INVISIBLE (-5225 2875);
FORCEADD OFFPAGE..5
R 2
(-5225 2775);
FORCEPROP 2 LAST $XR0 112 
J 0
(-5036 2775);
DISPLAY 0.638298 (-5036 2775);
PAINT MONO (-5036 2775);
FORCEPROP 2 LAST PATH I93
J 0
(-5050 2850);
DISPLAY 0.680851 (-5050 2850);
DISPLAY INVISIBLE (-5050 2850);
FORCEPROP 1 LAST COMMENT_BODY TRUE
J 2
(-5325 2700);
DISPLAY 0.872340 (-5325 2700);
PAINT GREEN (-5325 2700);
DISPLAY INVISIBLE (-5325 2700);
FORCEPROP 1 LAST OFFPAGE TRUE
J 2
(-5550 2650);
DISPLAY 0.872340 (-5550 2650);
PAINT GREEN (-5550 2650);
DISPLAY INVISIBLE (-5550 2650);
FORCEPROP 2 LAST CDS_LIB standard
J 0
(-5225 2775);
DISPLAY INVISIBLE (-5225 2775);
FORCEADD OFFPAGE..5
R 2
(-5225 2825);
FORCEPROP 2 LAST $XR0 112 
J 0
(-5036 2825);
DISPLAY 0.638298 (-5036 2825);
PAINT MONO (-5036 2825);
FORCEPROP 2 LAST PATH I94
J 0
(-5050 2900);
DISPLAY 0.680851 (-5050 2900);
DISPLAY INVISIBLE (-5050 2900);
FORCEPROP 1 LAST COMMENT_BODY TRUE
J 2
(-5325 2750);
DISPLAY 0.872340 (-5325 2750);
PAINT GREEN (-5325 2750);
DISPLAY INVISIBLE (-5325 2750);
FORCEPROP 1 LAST OFFPAGE TRUE
J 2
(-5550 2700);
DISPLAY 0.872340 (-5550 2700);
PAINT GREEN (-5550 2700);
DISPLAY INVISIBLE (-5550 2700);
FORCEPROP 2 LAST CDS_LIB standard
J 0
(-5225 2825);
DISPLAY INVISIBLE (-5225 2825);
FORCEADD Q_RES..1
(-6025 2925);
FORCEPROP 1 LAST LOCATION R1399
J 0
(-6375 2925);
DISPLAY 0.489362 (-6375 2925);
PAINT SKYBLUE (-6375 2925);
FORCEPROP 0 LAST $SEC 1
J 0
(-6175 2975);
DISPLAY 0.680851 (-6175 2975);
PAINT MONO (-6175 2975);
DISPLAY INVISIBLE (-6175 2975);
FORCEPROP 0 LAST CDS_SEC 1
J 0
(-6175 2975);
DISPLAY 0.680851 (-6175 2975);
DISPLAY INVISIBLE (-6175 2975);
FORCEPROP 1 LASTPIN (-6125 2925) $PN 1
J 0
(-6113 2937);
DISPLAY 0.489362 (-6113 2937);
PAINT MONO (-6113 2937);
FORCEPROP 1 LASTPIN (-5925 2925) $PN 2
J 0
(-5963 2937);
DISPLAY 0.489362 (-5963 2937);
PAINT MONO (-5963 2937);
FORCEPROP 1 LAST VALUE 0
J 2
(-5875 2925);
DISPLAY 0.489362 (-5875 2925);
PAINT SKYBLUE (-5875 2925);
FORCEPROP 1 LAST PACK_TYPE 0402LF
J 0
(-5950 2875);
DISPLAY 0.489362 (-5950 2875);
PAINT SKYBLUE (-5950 2875);
DISPLAY INVISIBLE (-5950 2875);
FORCEPROP 1 LAST PART_NUMBER CS00002JB38
J 0
(-5950 2975);
DISPLAY 0.489362 (-5950 2975);
PAINT SKYBLUE (-5950 2975);
DISPLAY INVISIBLE (-5950 2975);
FORCEPROP 1 LAST TOLERANCE 5%
J 0
(-6025 2875);
DISPLAY 0.489362 (-6025 2875);
PAINT SKYBLUE (-6025 2875);
DISPLAY INVISIBLE (-6025 2875);
FORCEPROP 1 LAST MATERIAL CHIP
J 0
(-5875 2925);
DISPLAY 0.489362 (-5875 2925);
PAINT SKYBLUE (-5875 2925);
DISPLAY INVISIBLE (-5875 2925);
FORCEPROP 1 LAST WATTAGE 1/16W
J 2
(-6050 2825);
DISPLAY 0.489362 (-6050 2825);
PAINT SKYBLUE (-6050 2825);
DISPLAY INVISIBLE (-6050 2825);
FORCEPROP 1 LAST PATH I96
J 0
(-6075 3075);
DISPLAY 0.978723 (-6075 3075);
PAINT WHITE (-6075 3075);
DISPLAY INVISIBLE (-6075 3075);
FORCEPROP 2 LAST CDS_LIB pure_quanta
J 0
(-6025 2925);
DISPLAY INVISIBLE (-6025 2925);
FORCEPROP 2 LAST BOM_COST OCP3.0 
J 0
(-5950 3025);
DISPLAY 0.680851 (-5950 3025);
DISPLAY INVISIBLE (-5950 3025);
FORCEADD Q_RES..1
(-6025 2875);
FORCEPROP 1 LAST LOCATION R1400
J 0
(-6375 2875);
DISPLAY 0.489362 (-6375 2875);
PAINT SKYBLUE (-6375 2875);
FORCEPROP 0 LAST $SEC 1
J 0
(-6175 2925);
DISPLAY 0.680851 (-6175 2925);
PAINT MONO (-6175 2925);
DISPLAY INVISIBLE (-6175 2925);
FORCEPROP 0 LAST CDS_SEC 1
J 0
(-6175 2925);
DISPLAY 0.680851 (-6175 2925);
DISPLAY INVISIBLE (-6175 2925);
FORCEPROP 1 LASTPIN (-6125 2875) $PN 1
J 0
(-6113 2887);
DISPLAY 0.489362 (-6113 2887);
PAINT MONO (-6113 2887);
FORCEPROP 1 LASTPIN (-5925 2875) $PN 2
J 0
(-5963 2887);
DISPLAY 0.489362 (-5963 2887);
PAINT MONO (-5963 2887);
FORCEPROP 1 LAST VALUE 0
J 2
(-5875 2875);
DISPLAY 0.489362 (-5875 2875);
PAINT SKYBLUE (-5875 2875);
FORCEPROP 1 LAST PACK_TYPE 0402LF
J 0
(-5950 2825);
DISPLAY 0.489362 (-5950 2825);
PAINT SKYBLUE (-5950 2825);
DISPLAY INVISIBLE (-5950 2825);
FORCEPROP 1 LAST PART_NUMBER CS00002JB38
J 0
(-5950 2925);
DISPLAY 0.489362 (-5950 2925);
PAINT SKYBLUE (-5950 2925);
DISPLAY INVISIBLE (-5950 2925);
FORCEPROP 1 LAST TOLERANCE 5%
J 0
(-6025 2825);
DISPLAY 0.489362 (-6025 2825);
PAINT SKYBLUE (-6025 2825);
DISPLAY INVISIBLE (-6025 2825);
FORCEPROP 1 LAST MATERIAL CHIP
J 0
(-5875 2875);
DISPLAY 0.489362 (-5875 2875);
PAINT SKYBLUE (-5875 2875);
DISPLAY INVISIBLE (-5875 2875);
FORCEPROP 1 LAST WATTAGE 1/16W
J 2
(-6050 2775);
DISPLAY 0.489362 (-6050 2775);
PAINT SKYBLUE (-6050 2775);
DISPLAY INVISIBLE (-6050 2775);
FORCEPROP 1 LAST PATH I97
J 0
(-6075 3025);
DISPLAY 0.978723 (-6075 3025);
PAINT WHITE (-6075 3025);
DISPLAY INVISIBLE (-6075 3025);
FORCEPROP 2 LAST CDS_LIB pure_quanta
J 0
(-6025 2875);
DISPLAY INVISIBLE (-6025 2875);
FORCEPROP 2 LAST BOM_COST OCP3.0 
J 0
(-5950 2975);
DISPLAY 0.680851 (-5950 2975);
DISPLAY INVISIBLE (-5950 2975);
FORCEADD Q_RES..1
(-6025 2825);
FORCEPROP 1 LAST LOCATION R1401
J 0
(-6375 2825);
DISPLAY 0.489362 (-6375 2825);
PAINT SKYBLUE (-6375 2825);
FORCEPROP 0 LAST $SEC 1
J 0
(-6175 2875);
DISPLAY 0.680851 (-6175 2875);
PAINT MONO (-6175 2875);
DISPLAY INVISIBLE (-6175 2875);
FORCEPROP 0 LAST CDS_SEC 1
J 0
(-6175 2875);
DISPLAY 0.680851 (-6175 2875);
DISPLAY INVISIBLE (-6175 2875);
FORCEPROP 1 LASTPIN (-6125 2825) $PN 1
J 0
(-6113 2837);
DISPLAY 0.489362 (-6113 2837);
PAINT MONO (-6113 2837);
FORCEPROP 1 LASTPIN (-5925 2825) $PN 2
J 0
(-5963 2837);
DISPLAY 0.489362 (-5963 2837);
PAINT MONO (-5963 2837);
FORCEPROP 1 LAST VALUE 0
J 2
(-5875 2825);
DISPLAY 0.489362 (-5875 2825);
PAINT SKYBLUE (-5875 2825);
FORCEPROP 1 LAST PACK_TYPE 0402LF
J 0
(-5950 2775);
DISPLAY 0.489362 (-5950 2775);
PAINT SKYBLUE (-5950 2775);
DISPLAY INVISIBLE (-5950 2775);
FORCEPROP 1 LAST PART_NUMBER CS00002JB38
J 0
(-5950 2875);
DISPLAY 0.489362 (-5950 2875);
PAINT SKYBLUE (-5950 2875);
DISPLAY INVISIBLE (-5950 2875);
FORCEPROP 1 LAST TOLERANCE 5%
J 0
(-6025 2775);
DISPLAY 0.489362 (-6025 2775);
PAINT SKYBLUE (-6025 2775);
DISPLAY INVISIBLE (-6025 2775);
FORCEPROP 1 LAST MATERIAL CHIP
J 0
(-5875 2825);
DISPLAY 0.489362 (-5875 2825);
PAINT SKYBLUE (-5875 2825);
DISPLAY INVISIBLE (-5875 2825);
FORCEPROP 1 LAST WATTAGE 1/16W
J 2
(-6050 2725);
DISPLAY 0.489362 (-6050 2725);
PAINT SKYBLUE (-6050 2725);
DISPLAY INVISIBLE (-6050 2725);
FORCEPROP 1 LAST PATH I98
J 0
(-6075 2975);
DISPLAY 0.978723 (-6075 2975);
PAINT WHITE (-6075 2975);
DISPLAY INVISIBLE (-6075 2975);
FORCEPROP 2 LAST CDS_LIB pure_quanta
J 0
(-6025 2825);
DISPLAY INVISIBLE (-6025 2825);
FORCEPROP 2 LAST BOM_COST OCP3.0 
J 0
(-5950 2925);
DISPLAY 0.680851 (-5950 2925);
DISPLAY INVISIBLE (-5950 2925);
FORCEADD Q_RES..1
(-6025 2775);
FORCEPROP 1 LAST LOCATION R1402
J 0
(-6375 2775);
DISPLAY 0.489362 (-6375 2775);
PAINT SKYBLUE (-6375 2775);
FORCEPROP 0 LAST $SEC 1
J 0
(-6175 2825);
DISPLAY 0.680851 (-6175 2825);
PAINT MONO (-6175 2825);
DISPLAY INVISIBLE (-6175 2825);
FORCEPROP 0 LAST CDS_SEC 1
J 0
(-6175 2825);
DISPLAY 0.680851 (-6175 2825);
DISPLAY INVISIBLE (-6175 2825);
FORCEPROP 1 LASTPIN (-6125 2775) $PN 1
J 0
(-6113 2787);
DISPLAY 0.489362 (-6113 2787);
PAINT MONO (-6113 2787);
FORCEPROP 1 LASTPIN (-5925 2775) $PN 2
J 0
(-5963 2787);
DISPLAY 0.489362 (-5963 2787);
PAINT MONO (-5963 2787);
FORCEPROP 1 LAST VALUE 0
J 2
(-5875 2775);
DISPLAY 0.489362 (-5875 2775);
PAINT SKYBLUE (-5875 2775);
FORCEPROP 1 LAST PACK_TYPE 0402LF
J 0
(-5950 2725);
DISPLAY 0.489362 (-5950 2725);
PAINT SKYBLUE (-5950 2725);
DISPLAY INVISIBLE (-5950 2725);
FORCEPROP 1 LAST PART_NUMBER CS00002JB38
J 0
(-5950 2825);
DISPLAY 0.489362 (-5950 2825);
PAINT SKYBLUE (-5950 2825);
DISPLAY INVISIBLE (-5950 2825);
FORCEPROP 1 LAST TOLERANCE 5%
J 0
(-6025 2725);
DISPLAY 0.489362 (-6025 2725);
PAINT SKYBLUE (-6025 2725);
DISPLAY INVISIBLE (-6025 2725);
FORCEPROP 1 LAST MATERIAL CHIP
J 0
(-5875 2775);
DISPLAY 0.489362 (-5875 2775);
PAINT SKYBLUE (-5875 2775);
DISPLAY INVISIBLE (-5875 2775);
FORCEPROP 1 LAST WATTAGE 1/16W
J 2
(-6050 2675);
DISPLAY 0.489362 (-6050 2675);
PAINT SKYBLUE (-6050 2675);
DISPLAY INVISIBLE (-6050 2675);
FORCEPROP 1 LAST PATH I99
J 0
(-6075 2925);
DISPLAY 0.978723 (-6075 2925);
PAINT WHITE (-6075 2925);
DISPLAY INVISIBLE (-6075 2925);
FORCEPROP 2 LAST CDS_LIB pure_quanta
J 0
(-6025 2775);
DISPLAY INVISIBLE (-6025 2775);
FORCEPROP 2 LAST BOM_COST OCP3.0 
J 0
(-5950 2875);
DISPLAY 0.680851 (-5950 2875);
DISPLAY INVISIBLE (-5950 2875);
FORCEADD QUANTA_TITLE_BLOCK_C..1
(0 0);
FORCEPROP 0 LAST CDS_CON_LAST_MODIFIED Fri Mar 11 14:52:51 2022
J 0
(-1885 15);
DISPLAY INVISIBLE (-1885 15);
FORCEPROP 1 LAST CUSTOM_TXT_CDS <CON_LAST_MODIFIED>
J 0
(-1885 15);
DISPLAY 0.978723 (-1885 15);
FORCEPROP 2 LAST CUSTOM_TXT_CDS <XR_PAGE_TITLE>
J 0
(-7890 5250);
DISPLAY 0.638298 (-7890 5250);
PAINT PINK (-7890 5250);
DISPLAY INVISIBLE (-7890 5250);
FORCEPROP 1 LAST CUSTOM_TXT_CDS <NAME_2>
J 0
(-3175 50);
FORCEPROP 1 LAST CUSTOM_TXT_CDS <NAME_1>
J 0
(-3175 175);
FORCEPROP 1 LAST CUSTOM_TXT_CDS <Q_NUMBER>
J 0
(-1403 103);
DISPLAY 1.212766 (-1403 103);
FORCEPROP 1 LAST CUSTOM_TXT_CDS <Q_PROJ>
J 0
(-2382 102);
DISPLAY 1.212766 (-2382 102);
FORCEPROP 1 LAST CUSTOM_TXT_CDS <Q_REV>
J 0
(-184 103);
DISPLAY 1.212766 (-184 103);
FORCEPROP 1 LAST CUSTOM_TXT_CDS <CON_PAGE_NUM> OF <CON_TOTAL_PAGES>
J 0
(-446 18);
DISPLAY 0.978723 (-446 18);
FORCEPROP 1 LAST Q_DEPT BU9
J 1
(-3763 49);
DISPLAY 1.957447 (-3763 49);
PAINT GREEN (-3763 49);
FORCEPROP 1 LAST Q_TITLE FPGA 5/6
J 0
(-9275 75);
DISPLAY 2.446809 (-9275 75);
PAINT GREEN (-9275 75);
FORCEPROP 1 LAST COMMENT_BODY TRUE
J 0
(12 -13);
DISPLAY 0.978723 (12 -13);
PAINT GREEN (12 -13);
DISPLAY INVISIBLE (12 -13);
FORCEPROP 2 LAST PAGE_BORDER TRUE
J 0
(-7890 5250);
DISPLAY 0.638298 (-7890 5250);
PAINT PINK (-7890 5250);
DISPLAY INVISIBLE (-7890 5250);
FORCEPROP 2 LAST CDS_LIB pure_quanta
J 0
(0 0);
DISPLAY INVISIBLE (0 0);
FORCEPROP 1 LAST CDS_LMAN_SYM_OUTLINE -9475,6775,100,-125
J 0
(0 0);
DISPLAY 0.468085 (0 0);
PAINT GREEN (0 0);
DISPLAY INVISIBLE (0 0);
FORCEPROP 2 LAST CDS_XR_PAGE_TITLE CR-83 : @T6G_MB_LIB.T6G(SCH_1):PAGE83
J 0
(-7890 5250);
DISPLAY 0.638298 (-7890 5250);
PAINT PINK (-7890 5250);
DISPLAY INVISIBLE (-7890 5250);
WIRE 16 -1 (-6450 1875)(-6450 2000);
WIRE 16 -1 (-8275 1850)(-8275 1900);
WIRE 16 -1 (-8250 1025)(-8250 1075);
WIRE 16 -1 (-2950 1625)(-2950 1750);
WIRE 16 -1 (-5850 4650)(-5850 4775);
WIRE 16 -1 (-2975 4750)(-2975 4700);
WIRE 16 -1 (-2975 3950)(-2975 3875);
WIRE 16 -1 (-6450 1050)(-6450 1175);
WIRE 16 -1 (-3550 4475)(-3550 4400);
WIRE 16 -1 (-3550 3700)(-3550 3550);
WIRE 16 -1 (-2475 3950)(-2475 3800);
WIRE 16 -1 (-7425 1425)(-7550 1425);
WIRE 16 -1 (-7550 1425)(-7550 1275);
WIRE 16 -1 (-7900 1625)(-7900 1675);
WIRE 16 -1 (-7900 800)(-7900 850);
WIRE 16 -1 (-7425 600)(-7550 600);
WIRE 16 -1 (-7550 600)(-7550 450);
WIRE 16 -1 (-2975 3025)(-2975 3150);
WIRE 16 -1 (-6200 6150)(-6200 6300);
WIRE 16 -1 (-8650 6075)(-8650 6150);
WIRE 16 -1 (-7275 5825)(-7225 5825);
WIRE 16 -1 (-8000 5825)(-7875 5825);
WIRE 16 -1 (-7950 5450)(-7950 5375);
WIRE 16 -1 (-7350 4200)(-7425 4200);
WIRE 16 -1 (-7425 4200)(-7425 4075);
WIRE 16 -1 (-7775 4475)(-7775 4525);
WIRE 16 -1 (-7825 3150)(-7825 3200);
WIRE 16 -1 (-7400 2875)(-7475 2875);
WIRE 16 -1 (-7475 2875)(-7475 2750);
WIRE 16 -1 (-3550 4200)(-3550 4050);
WIRE 16 -1 (-3125 4050)(-3550 4050);
FORCEPROP 2 LAST SIG_NAME SCM_PRSNT0_N
J 0
(-3510 4060);
DISPLAY 0.489362 (-3510 4060);
WIRE 16 -1 (-3550 4050)(-3550 3900);
WIRE 16 -1 (-3550 4050)(-3725 4050);
WIRE 16 -1 (-2975 4250)(-2975 4300);
WIRE 16 -1 (-2475 4300)(-2975 4300);
WIRE 16 -1 (-2975 4300)(-2975 4500);
WIRE 16 -1 (-2200 4300)(-2475 4300);
FORCEPROP 2 LAST SIG_NAME SCM_PRSNT0_R
J 2
(-2385 4310);
DISPLAY 0.489362 (-2385 4310);
FORCEPROP 2 LASTPROP $XRERR UNIQUE?
J 0
(-2625 4310);
DISPLAY 0.638298 (-2625 4310);
PAINT MONO (-2625 4310);
DISPLAY INVISIBLE (-2625 4310);
WIRE 16 -1 (-2475 4300)(-2475 4150);
WIRE 16 -1 (-7900 1875)(-7900 1950);
WIRE 16 -1 (-7550 1950)(-7900 1950);
WIRE 16 -1 (-7900 1975)(-7900 1950);
WIRE 16 -1 (-7550 1950)(-7550 1625);
WIRE 16 -1 (-7550 1625)(-7425 1625);
WIRE 16 -1 (-7550 1125)(-7550 800);
WIRE 16 -1 (-7550 1125)(-7900 1125);
WIRE 16 -1 (-7550 800)(-7425 800);
WIRE 16 -1 (-7900 1150)(-7900 1125);
WIRE 16 -1 (-7900 1050)(-7900 1125);
WIRE 16 -1 (-2975 2075)(-3350 2075);
WIRE 16 -1 (-2975 2350)(-2975 2075);
WIRE 16 -1 (-3350 2125)(-3350 2075);
WIRE 16 -1 (-3350 2075)(-3350 2025);
WIRE 16 -1 (-2950 675)(-3325 675);
WIRE 16 -1 (-2950 950)(-2950 675);
WIRE 16 -1 (-3325 675)(-3325 625);
WIRE 16 -1 (-3325 725)(-3325 675);
WIRE 16 -1 (-7900 4725)(-7900 4775);
WIRE 16 -1 (-7775 4775)(-7900 4775);
WIRE 16 -1 (-7775 4775)(-7425 4775);
WIRE 16 -1 (-7775 4875)(-7775 4775);
WIRE 16 -1 (-7775 4775)(-7775 4725);
WIRE 16 -1 (-7425 4775)(-7425 4400);
WIRE 16 -1 (-7425 4400)(-7350 4400);
WIRE 16 -1 (-7950 3400)(-7950 3450);
WIRE 16 -1 (-7825 3450)(-7950 3450);
WIRE 16 -1 (-7825 3450)(-7475 3450);
WIRE 16 -1 (-7825 3550)(-7825 3450);
WIRE 16 -1 (-7825 3450)(-7825 3400);
WIRE 16 -1 (-7475 3450)(-7475 3075);
WIRE 16 -1 (-7475 3075)(-7400 3075);
WIRE 16 -1 (-8250 825)(-8250 700);
WIRE 16 -1 (-8250 700)(-7425 700);
WIRE 16 -1 (-8675 700)(-8250 700);
FORCEPROP 0 LAST SIG_NAME FAN_DR_FAIL_N
J 0
(-8675 710);
DISPLAY 0.489362 (-8675 710);
WIRE 16 -1 (-8275 1650)(-8275 1525);
WIRE 16 -1 (-8275 1525)(-7425 1525);
WIRE 16 -1 (-8675 1525)(-8275 1525);
FORCEPROP 0 LAST SIG_NAME FAN_SR_FAIL_N
J 0
(-8675 1535);
DISPLAY 0.489362 (-8675 1535);
WIRE 16 -1 (-7875 5725)(-8650 5725);
FORCEPROP 2 LAST SIG_NAME FPGA_RDY_N
J 0
(-8435 5735);
DISPLAY 0.489362 (-8435 5735);
WIRE 16 -1 (-8650 5725)(-8650 5875);
WIRE 16 -1 (-8650 5725)(-8700 5725);
WIRE 16 -1 (-7950 2975)(-7950 3200);
WIRE 16 -1 (-7950 2975)(-7400 2975);
WIRE 16 -1 (-7950 2975)(-8675 2975);
FORCEPROP 2 LAST SIG_NAME FM_CLK_BUFFER_EN
J 0
(-8410 2985);
DISPLAY 0.489362 (-8410 2985);
WIRE 16 -1 (-6450 850)(-6450 700);
WIRE 16 -1 (-6450 700)(-6025 700);
WIRE 16 -1 (-7075 700)(-6450 700);
FORCEPROP 2 LAST SIG_NAME FM_FAN_DR_FAIL_R_N
J 0
(-6985 710);
DISPLAY 0.489362 (-6985 710);
FORCEPROP 2 LASTPROP $XRERR UNIQUE?
J 0
(-7225 710);
DISPLAY 0.638298 (-7225 710);
PAINT MONO (-7225 710);
DISPLAY INVISIBLE (-7225 710);
WIRE 16 -1 (-6450 1525)(-6050 1525);
WIRE 16 -1 (-6450 1525)(-6450 1675);
WIRE 16 -1 (-7075 1525)(-6450 1525);
FORCEPROP 2 LAST SIG_NAME FM_FAN_SR_FAIL_R_N
J 0
(-6960 1535);
DISPLAY 0.489362 (-6960 1535);
FORCEPROP 2 LASTPROP $XRERR UNIQUE?
J 0
(-7200 1535);
DISPLAY 0.638298 (-7200 1535);
PAINT MONO (-7200 1535);
DISPLAY INVISIBLE (-7200 1535);
WIRE 16 -1 (-6500 2775)(-6125 2775);
WIRE 16 -1 (-6500 2825)(-6500 2775);
WIRE 16 -1 (-6500 2825)(-6125 2825);
WIRE 16 -1 (-6500 2875)(-6500 2825);
WIRE 16 -1 (-6500 2875)(-6125 2875);
WIRE 16 -1 (-6500 2925)(-6500 2875);
WIRE 16 -1 (-6500 2925)(-6125 2925);
WIRE 16 -1 (-6500 2975)(-6500 2925);
WIRE 16 -1 (-6125 2975)(-6500 2975);
WIRE 16 -1 (-6500 2975)(-7050 2975);
FORCEPROP 2 LAST SIG_NAME FM_CLK_BUFFER_BUF_EN
J 0
(-7010 2985);
DISPLAY 0.489362 (-7010 2985);
FORCEPROP 2 LASTPROP $XRERR UNIQUE?
J 0
(-7250 2985);
DISPLAY 0.638298 (-7250 2985);
PAINT MONO (-7250 2985);
DISPLAY INVISIBLE (-7250 2985);
WIRE 16 -1 (-5850 1525)(-4825 1525);
FORCEPROP 0 LAST SIG_NAME FM_FAN_SR_FAIL_N
J 0
(-5410 1535);
DISPLAY 0.489362 (-5410 1535);
WIRE 16 -1 (-5825 700)(-4825 700);
FORCEPROP 0 LAST SIG_NAME FM_FAN_DR_FAIL_N
J 0
(-5385 735);
DISPLAY 0.489362 (-5385 735);
WIRE 16 -1 (-5275 2975)(-5925 2975);
FORCEPROP 2 LAST SIG_NAME FM_CLK_BUFFER0_EN
J 0
(-5685 2985);
DISPLAY 0.489362 (-5685 2985);
WIRE 16 -1 (-5275 2925)(-5925 2925);
FORCEPROP 2 LAST SIG_NAME FM_CLK_BUFFER1_EN
J 0
(-5685 2935);
DISPLAY 0.489362 (-5685 2935);
WIRE 16 -1 (-5275 2875)(-5925 2875);
FORCEPROP 2 LAST SIG_NAME FM_CLK_BUFFER2_EN
J 0
(-5685 2885);
DISPLAY 0.489362 (-5685 2885);
WIRE 16 -1 (-5275 2775)(-5925 2775);
FORCEPROP 2 LAST SIG_NAME FM_CLK_BUFFER4_EN
J 0
(-5685 2785);
DISPLAY 0.489362 (-5685 2785);
WIRE 16 -1 (-5275 2825)(-5925 2825);
FORCEPROP 2 LAST SIG_NAME FM_CLK_BUFFER3_EN
J 0
(-5685 2835);
DISPLAY 0.489362 (-5685 2835);
WIRE 16 -1 (-7900 4300)(-7350 4300);
WIRE 16 -1 (-7900 4300)(-7900 4525);
WIRE 16 -1 (-8625 4300)(-7900 4300);
FORCEPROP 2 LAST SIG_NAME SCM_IRQ_1V8_N
J 0
(-8610 4310);
DISPLAY 0.489362 (-8610 4310);
WIRE 16 -1 (-7875 5775)(-7950 5775);
WIRE 16 -1 (-7950 5650)(-7950 5775);
WIRE 16 -1 (-7950 5775)(-8700 5775);
FORCEPROP 2 LAST SIG_NAME FPGA_RDY
J 0
(-8435 5785);
DISPLAY 0.489362 (-8435 5785);
WIRE 16 -1 (-6650 5725)(-7275 5725);
FORCEPROP 2 LAST SIG_NAME FPGA_RDY_R_N
J 0
(-7110 5735);
DISPLAY 0.489362 (-7110 5735);
FORCEPROP 2 LASTPROP $XRERR UNIQUE?
J 0
(-7350 5735);
DISPLAY 0.638298 (-7350 5735);
PAINT MONO (-7350 5735);
DISPLAY INVISIBLE (-7350 5735);
WIRE 16 -1 (-7275 5775)(-6500 5775);
FORCEPROP 2 LAST SIG_NAME FPGA_RDY_N
J 0
(-6760 5785);
DISPLAY 0.489362 (-6760 5785);
WIRE 16 -1 (-7000 4300)(-6525 4300);
FORCEPROP 2 LAST SIG_NAME SCM_IRQ_R_N
J 0
(-6860 4310);
DISPLAY 0.489362 (-6860 4310);
FORCEPROP 2 LASTPROP $XRERR UNIQUE?
J 0
(-7100 4310);
DISPLAY 0.638298 (-7100 4310);
PAINT MONO (-7100 4310);
DISPLAY INVISIBLE (-7100 4310);
WIRE 16 -1 (-6450 5725)(-6200 5725);
WIRE 16 -1 (-5625 5725)(-6200 5725);
FORCEPROP 2 LAST SIG_NAME HPM_STBY_RDY
J 0
(-6035 5735);
DISPLAY 0.489362 (-6035 5735);
WIRE 16 -1 (-6200 5725)(-6200 5950);
WIRE 16 -1 (-5850 4300)(-5850 4450);
WIRE 16 -1 (-5850 4300)(-5750 4300);
WIRE 16 -1 (-6325 4300)(-5850 4300);
FORCEPROP 2 LAST SIG_NAME SCM_IRQ_N
J 0
(-6185 4310);
DISPLAY 0.489362 (-6185 4310);
WIRE 16 -1 (-3325 925)(-3325 1050);
WIRE 16 -1 (-3325 1050)(-3150 1050);
WIRE 16 -1 (-3825 1050)(-3325 1050);
FORCEPROP 2 LAST SIG_NAME FM_FAN_DR_FULL_SPEED
J 0
(-3760 1075);
DISPLAY 0.489362 (-3760 1075);
WIRE 16 -1 (-2950 1250)(-2950 1350);
WIRE 16 -1 (-2950 1350)(-2100 1350);
FORCEPROP 2 LAST SIG_NAME FAN_DR_FULL_SPEED_N
J 0
(-2835 1360);
DISPLAY 0.489362 (-2835 1360);
FORCEPROP 2 LASTPROP $XRERR UNIQUE?
J 0
(-3075 1360);
DISPLAY 0.638298 (-3075 1360);
PAINT MONO (-3075 1360);
DISPLAY INVISIBLE (-3075 1360);
WIRE 16 -1 (-2950 1425)(-2950 1350);
WIRE 16 -1 (-3350 2325)(-3350 2450);
WIRE 16 -1 (-3350 2450)(-3175 2450);
WIRE 16 -1 (-3850 2450)(-3350 2450);
FORCEPROP 2 LAST SIG_NAME FM_FAN_SR_FULL_SPEED
J 0
(-3785 2475);
DISPLAY 0.489362 (-3785 2475);
WIRE 16 -1 (-2975 2650)(-2975 2750);
WIRE 16 -1 (-2975 2750)(-2075 2750);
FORCEPROP 2 LAST SIG_NAME FAN_SR_FULL_SPEED_N
J 0
(-2860 2760);
DISPLAY 0.489362 (-2860 2760);
FORCEPROP 2 LASTPROP $XRERR UNIQUE?
J 0
(-3100 2760);
DISPLAY 0.638298 (-3100 2760);
PAINT MONO (-3100 2760);
DISPLAY INVISIBLE (-3100 2760);
WIRE 16 -1 (-2975 2825)(-2975 2750);
WIRE 16 -1 (-1900 1350)(-1025 1350);
FORCEPROP 2 LAST SIG_NAME FAN_DR_FULL_SPEED_N_R
J 0
(-1800 1360);
DISPLAY 0.489362 (-1800 1360);
WIRE 16 -1 (-1875 2750)(-1000 2750);
FORCEPROP 2 LAST SIG_NAME FAN_SR_FULL_SPEED_N_R
J 0
(-1760 2760);
DISPLAY 0.489362 (-1760 2760);
WIRE 16 -1 (-1525 4300)(-2000 4300);
FORCEPROP 2 LAST SIG_NAME SCM_PRSNT0
J 2
(-1635 4310);
DISPLAY 0.489362 (-1635 4310);
CIRCLE (-7275 3000)(-6779 3000);
PAINT YELLOW (-7275 3000);
DOT 1 (-6500 2825);
DOT 1 (-6500 2925);
DOT 1 (-8650 5725);
DOT 1 (-7950 5775);
DOT 1 (-6200 5725);
DOT 1 (-6500 2875);
DOT 1 (-7950 2975);
DOT 1 (-7825 3450);
DOT 1 (-6500 2975);
DOT 1 (-3350 2450);
DOT 1 (-3350 2075);
DOT 1 (-3325 1050);
DOT 1 (-3325 675);
DOT 1 (-2975 2750);
DOT 1 (-2950 1350);
DOT 1 (-7900 4300);
DOT 1 (-7775 4775);
DOT 1 (-5850 4300);
DOT 1 (-8250 700);
DOT 1 (-8275 1525);
DOT 1 (-7900 1125);
DOT 1 (-7900 1950);
DOT 1 (-6450 700);
DOT 1 (-6450 1525);
DOT 1 (-2975 4300);
DOT 1 (-2475 4300);
DOT 1 (-3550 4050);
FORCENOTE
VGS:1.2V
(-3475 3925) 0;
DISPLAY LEFT (-3475 3925);
DISPLAY 1.021277 (-3475 3925);
PAINT WHITE (-3475 3925);
QUIT
